(kicad_sch
	(version 20250114)
	(generator "eeschema")
	(generator_version "9.0")
	(paper "A3")
	(title_block
		(title "Kintex 410T devboard")
		(date "2024-04-03")
		(rev "1.1.2")
	)
	(junction
		(at 140.97 69.85)
		(diameter 0)
		(color 0 0 0 0)
	)
	(junction
		(at 241.3 69.85)
		(diameter 0)
		(color 0 0 0 0)
	)
	(junction
		(at 148.59 80.01)
		(diameter 0)
		(color 0 0 0 0)
	)
	(junction
		(at 279.4 69.85)
		(diameter 0)
		(color 0 0 0 0)
	)
	(junction
		(at 248.92 69.85)
		(diameter 0)
		(color 0 0 0 0)
	)
	(junction
		(at 287.02 69.85)
		(diameter 0)
		(color 0 0 0 0)
	)
	(junction
		(at 125.73 80.01)
		(diameter 0)
		(color 0 0 0 0)
	)
	(junction
		(at 156.21 80.01)
		(diameter 0)
		(color 0 0 0 0)
	)
	(junction
		(at 248.92 80.01)
		(diameter 0)
		(color 0 0 0 0)
	)
	(junction
		(at 125.73 69.85)
		(diameter 0)
		(color 0 0 0 0)
	)
	(junction
		(at 271.78 80.01)
		(diameter 0)
		(color 0 0 0 0)
	)
	(junction
		(at 140.97 80.01)
		(diameter 0)
		(color 0 0 0 0)
	)
	(junction
		(at 163.83 80.01)
		(diameter 0)
		(color 0 0 0 0)
	)
	(junction
		(at 156.21 69.85)
		(diameter 0)
		(color 0 0 0 0)
	)
	(junction
		(at 133.35 69.85)
		(diameter 0)
		(color 0 0 0 0)
	)
	(junction
		(at 133.35 80.01)
		(diameter 0)
		(color 0 0 0 0)
	)
	(junction
		(at 279.4 80.01)
		(diameter 0)
		(color 0 0 0 0)
	)
	(junction
		(at 264.16 69.85)
		(diameter 0)
		(color 0 0 0 0)
	)
	(junction
		(at 148.59 69.85)
		(diameter 0)
		(color 0 0 0 0)
	)
	(junction
		(at 163.83 69.85)
		(diameter 0)
		(color 0 0 0 0)
	)
	(junction
		(at 264.16 80.01)
		(diameter 0)
		(color 0 0 0 0)
	)
	(junction
		(at 271.78 69.85)
		(diameter 0)
		(color 0 0 0 0)
	)
	(junction
		(at 287.02 80.01)
		(diameter 0)
		(color 0 0 0 0)
	)
	(junction
		(at 256.54 80.01)
		(diameter 0)
		(color 0 0 0 0)
	)
	(junction
		(at 256.54 69.85)
		(diameter 0)
		(color 0 0 0 0)
	)
	(junction
		(at 171.45 69.85)
		(diameter 0)
		(color 0 0 0 0)
	)
	(no_connect
		(at 233.68 170.18)
	)
	(no_connect
		(at 233.68 203.2)
	)
	(no_connect
		(at 233.68 223.52)
	)
	(no_connect
		(at 233.68 213.36)
	)
	(no_connect
		(at 233.68 195.58)
	)
	(no_connect
		(at 233.68 182.88)
	)
	(no_connect
		(at 177.8 190.5)
	)
	(no_connect
		(at 233.68 200.66)
	)
	(no_connect
		(at 233.68 149.86)
	)
	(no_connect
		(at 233.68 198.12)
	)
	(no_connect
		(at 233.68 104.14)
	)
	(no_connect
		(at 233.68 185.42)
	)
	(no_connect
		(at 233.68 165.1)
	)
	(no_connect
		(at 233.68 210.82)
	)
	(no_connect
		(at 233.68 193.04)
	)
	(no_connect
		(at 233.68 167.64)
	)
	(no_connect
		(at 233.68 177.8)
	)
	(bus_entry
		(at 157.48 228.6)
		(size -1.27 1.27)
		(stroke
			(width 0)
			(type default)
		)
	)
	(bus_entry
		(at 248.92 153.67)
		(size -1.27 1.27)
		(stroke
			(width 0)
			(type default)
		)
	)
	(bus_entry
		(at 120.65 176.53)
		(size 1.27 1.27)
		(stroke
			(width 0)
			(type default)
		)
	)
	(bus_entry
		(at 312.42 128.27)
		(size -1.27 1.27)
		(stroke
			(width 0)
			(type default)
		)
	)
	(bus_entry
		(at 261.62 172.72)
		(size 1.27 -1.27)
		(stroke
			(width 0)
			(type default)
		)
	)
	(bus_entry
		(at 120.65 179.07)
		(size 1.27 1.27)
		(stroke
			(width 0)
			(type default)
		)
	)
	(bus_entry
		(at 266.7 208.28)
		(size -1.27 0)
		(stroke
			(width 0)
			(type default)
		)
	)
	(bus_entry
		(at 120.65 181.61)
		(size 1.27 1.27)
		(stroke
			(width 0)
			(type default)
		)
	)
	(bus_entry
		(at 157.48 226.06)
		(size -1.27 1.27)
		(stroke
			(width 0)
			(type default)
		)
	)
	(bus_entry
		(at 120.65 120.65)
		(size 1.27 1.27)
		(stroke
			(width 0)
			(type default)
		)
	)
	(bus_entry
		(at 312.42 105.41)
		(size -1.27 1.27)
		(stroke
			(width 0)
			(type default)
		)
	)
	(bus_entry
		(at 120.65 171.45)
		(size 1.27 1.27)
		(stroke
			(width 0)
			(type default)
		)
	)
	(bus_entry
		(at 120.65 217.17)
		(size 1.27 1.27)
		(stroke
			(width 0)
			(type default)
		)
	)
	(bus_entry
		(at 105.41 168.91)
		(size 1.27 1.27)
		(stroke
			(width 0)
			(type default)
		)
	)
	(bus_entry
		(at 120.65 107.95)
		(size 1.27 1.27)
		(stroke
			(width 0)
			(type default)
		)
	)
	(bus_entry
		(at 285.75 204.47)
		(size -1.27 1.27)
		(stroke
			(width 0)
			(type default)
		)
	)
	(bus_entry
		(at 157.48 198.12)
		(size -1.27 1.27)
		(stroke
			(width 0)
			(type default)
		)
	)
	(bus_entry
		(at 312.42 107.95)
		(size -1.27 1.27)
		(stroke
			(width 0)
			(type default)
		)
	)
	(bus_entry
		(at 120.65 156.21)
		(size 1.27 1.27)
		(stroke
			(width 0)
			(type default)
		)
	)
	(bus_entry
		(at 285.75 120.65)
		(size -1.27 1.27)
		(stroke
			(width 0)
			(type default)
		)
	)
	(bus_entry
		(at 157.48 203.2)
		(size -1.27 1.27)
		(stroke
			(width 0)
			(type default)
		)
	)
	(bus_entry
		(at 312.42 143.51)
		(size -1.27 1.27)
		(stroke
			(width 0)
			(type default)
		)
	)
	(bus_entry
		(at 120.65 143.51)
		(size 1.27 1.27)
		(stroke
			(width 0)
			(type default)
		)
	)
	(bus_entry
		(at 312.42 140.97)
		(size -1.27 1.27)
		(stroke
			(width 0)
			(type default)
		)
	)
	(bus_entry
		(at 120.65 128.27)
		(size 1.27 1.27)
		(stroke
			(width 0)
			(type default)
		)
	)
	(bus_entry
		(at 120.65 138.43)
		(size 1.27 1.27)
		(stroke
			(width 0)
			(type default)
		)
	)
	(bus_entry
		(at 312.42 214.63)
		(size -1.27 1.27)
		(stroke
			(width 0)
			(type default)
		)
	)
	(bus_entry
		(at 120.65 113.03)
		(size 1.27 1.27)
		(stroke
			(width 0)
			(type default)
		)
	)
	(bus_entry
		(at 260.35 226.06)
		(size -1.27 0)
		(stroke
			(width 0)
			(type default)
		)
	)
	(bus_entry
		(at 120.65 186.69)
		(size 1.27 1.27)
		(stroke
			(width 0)
			(type default)
		)
	)
	(bus_entry
		(at 334.01 217.17)
		(size -1.27 1.27)
		(stroke
			(width 0)
			(type default)
		)
	)
	(bus_entry
		(at 285.75 173.99)
		(size -1.27 1.27)
		(stroke
			(width 0)
			(type default)
		)
	)
	(bus_entry
		(at 120.65 146.05)
		(size 1.27 1.27)
		(stroke
			(width 0)
			(type default)
		)
	)
	(bus_entry
		(at 285.75 189.23)
		(size -1.27 1.27)
		(stroke
			(width 0)
			(type default)
		)
	)
	(bus_entry
		(at 345.44 147.32)
		(size -1.27 0)
		(stroke
			(width 0)
			(type default)
		)
	)
	(bus_entry
		(at 120.65 135.89)
		(size 1.27 1.27)
		(stroke
			(width 0)
			(type default)
		)
	)
	(bus_entry
		(at 261.62 162.56)
		(size 1.27 -1.27)
		(stroke
			(width 0)
			(type default)
		)
	)
	(bus_entry
		(at 120.65 105.41)
		(size 1.27 1.27)
		(stroke
			(width 0)
			(type default)
		)
	)
	(bus_entry
		(at 120.65 133.35)
		(size 1.27 1.27)
		(stroke
			(width 0)
			(type default)
		)
	)
	(bus_entry
		(at 120.65 110.49)
		(size 1.27 1.27)
		(stroke
			(width 0)
			(type default)
		)
	)
	(bus_entry
		(at 157.48 215.9)
		(size -1.27 1.27)
		(stroke
			(width 0)
			(type default)
		)
	)
	(bus_entry
		(at 120.65 148.59)
		(size 1.27 1.27)
		(stroke
			(width 0)
			(type default)
		)
	)
	(bus_entry
		(at 157.48 220.98)
		(size -1.27 1.27)
		(stroke
			(width 0)
			(type default)
		)
	)
	(bus_entry
		(at 248.92 151.13)
		(size -1.27 1.27)
		(stroke
			(width 0)
			(type default)
		)
	)
	(bus_entry
		(at 334.01 219.71)
		(size -1.27 1.27)
		(stroke
			(width 0)
			(type default)
		)
	)
	(bus_entry
		(at 120.65 130.81)
		(size 1.27 1.27)
		(stroke
			(width 0)
			(type default)
		)
	)
	(bus_entry
		(at 120.65 161.29)
		(size 1.27 1.27)
		(stroke
			(width 0)
			(type default)
		)
	)
	(bus_entry
		(at 248.92 133.35)
		(size -1.27 1.27)
		(stroke
			(width 0)
			(type default)
		)
	)
	(bus_entry
		(at 285.75 130.81)
		(size -1.27 1.27)
		(stroke
			(width 0)
			(type default)
		)
	)
	(bus_entry
		(at 120.65 158.75)
		(size 1.27 1.27)
		(stroke
			(width 0)
			(type default)
		)
	)
	(bus_entry
		(at 285.75 110.49)
		(size -1.27 1.27)
		(stroke
			(width 0)
			(type default)
		)
	)
	(bus_entry
		(at 120.65 168.91)
		(size 1.27 1.27)
		(stroke
			(width 0)
			(type default)
		)
	)
	(bus_entry
		(at 91.44 186.69)
		(size 1.27 1.27)
		(stroke
			(width 0)
			(type default)
		)
	)
	(bus_entry
		(at 120.65 123.19)
		(size 1.27 1.27)
		(stroke
			(width 0)
			(type default)
		)
	)
	(bus_entry
		(at 120.65 125.73)
		(size 1.27 1.27)
		(stroke
			(width 0)
			(type default)
		)
	)
	(bus_entry
		(at 120.65 115.57)
		(size 1.27 1.27)
		(stroke
			(width 0)
			(type default)
		)
	)
	(bus_entry
		(at 312.42 118.11)
		(size -1.27 1.27)
		(stroke
			(width 0)
			(type default)
		)
	)
	(bus_entry
		(at 120.65 153.67)
		(size 1.27 1.27)
		(stroke
			(width 0)
			(type default)
		)
	)
	(bus_entry
		(at 105.41 143.51)
		(size 1.27 1.27)
		(stroke
			(width 0)
			(type default)
		)
	)
	(bus_entry
		(at 285.75 186.69)
		(size -1.27 1.27)
		(stroke
			(width 0)
			(type default)
		)
	)
	(bus_entry
		(at 260.35 180.34)
		(size 1.27 0)
		(stroke
			(width 0)
			(type default)
		)
	)
	(bus_entry
		(at 120.65 118.11)
		(size 1.27 1.27)
		(stroke
			(width 0)
			(type default)
		)
	)
	(bus_entry
		(at 120.65 173.99)
		(size 1.27 1.27)
		(stroke
			(width 0)
			(type default)
		)
	)
	(bus_entry
		(at 312.42 115.57)
		(size -1.27 1.27)
		(stroke
			(width 0)
			(type default)
		)
	)
	(bus_entry
		(at 157.48 223.52)
		(size -1.27 1.27)
		(stroke
			(width 0)
			(type default)
		)
	)
	(bus_entry
		(at 120.65 184.15)
		(size 1.27 1.27)
		(stroke
			(width 0)
			(type default)
		)
	)
	(bus_entry
		(at 248.92 138.43)
		(size -1.27 1.27)
		(stroke
			(width 0)
			(type default)
		)
	)
	(bus_entry
		(at 120.65 194.31)
		(size 1.27 1.27)
		(stroke
			(width 0)
			(type default)
		)
	)
	(bus_entry
		(at 248.92 135.89)
		(size -1.27 1.27)
		(stroke
			(width 0)
			(type default)
		)
	)
	(bus_entry
		(at 248.92 158.75)
		(size -1.27 1.27)
		(stroke
			(width 0)
			(type default)
		)
	)
	(bus_entry
		(at 157.48 193.04)
		(size -1.27 1.27)
		(stroke
			(width 0)
			(type default)
		)
	)
	(bus_entry
		(at 285.75 156.21)
		(size -1.27 1.27)
		(stroke
			(width 0)
			(type default)
		)
	)
	(bus_entry
		(at 157.48 167.64)
		(size -1.27 1.27)
		(stroke
			(width 0)
			(type default)
		)
	)
	(bus_entry
		(at 157.48 213.36)
		(size -1.27 1.27)
		(stroke
			(width 0)
			(type default)
		)
	)
	(bus_entry
		(at 248.92 125.73)
		(size -1.27 1.27)
		(stroke
			(width 0)
			(type default)
		)
	)
	(bus_entry
		(at 157.48 200.66)
		(size -1.27 1.27)
		(stroke
			(width 0)
			(type default)
		)
	)
	(bus_entry
		(at 120.65 102.87)
		(size 1.27 1.27)
		(stroke
			(width 0)
			(type default)
		)
	)
	(bus_entry
		(at 120.65 163.83)
		(size 1.27 1.27)
		(stroke
			(width 0)
			(type default)
		)
	)
	(bus_entry
		(at 334.01 123.19)
		(size -1.27 1.27)
		(stroke
			(width 0)
			(type default)
		)
	)
	(bus_entry
		(at 120.65 151.13)
		(size 1.27 1.27)
		(stroke
			(width 0)
			(type default)
		)
	)
	(bus_entry
		(at 120.65 140.97)
		(size 1.27 1.27)
		(stroke
			(width 0)
			(type default)
		)
	)
	(bus_entry
		(at 120.65 207.01)
		(size 1.27 1.27)
		(stroke
			(width 0)
			(type default)
		)
	)
	(bus_entry
		(at 157.48 205.74)
		(size -1.27 1.27)
		(stroke
			(width 0)
			(type default)
		)
	)
	(bus_entry
		(at 91.44 163.83)
		(size 1.27 1.27)
		(stroke
			(width 0)
			(type default)
		)
	)
	(bus_entry
		(at 248.92 113.03)
		(size -1.27 1.27)
		(stroke
			(width 0)
			(type default)
		)
	)
	(bus_entry
		(at 120.65 209.55)
		(size 1.27 1.27)
		(stroke
			(width 0)
			(type default)
		)
	)
	(wire
		(pts
			(xy 177.8 121.92) (xy 121.92 121.92)
		)
		(stroke
			(width 0)
			(type default)
		)
	)
	(wire
		(pts
			(xy 157.48 220.98) (xy 177.8 220.98)
		)
		(stroke
			(width 0)
			(type default)
		)
	)
	(wire
		(pts
			(xy 171.45 80.01) (xy 163.83 80.01)
		)
		(stroke
			(width 0)
			(type default)
		)
	)
	(wire
		(pts
			(xy 233.68 226.06) (xy 259.08 226.06)
		)
		(stroke
			(width 0)
			(type default)
		)
	)
	(wire
		(pts
			(xy 171.45 80.01) (xy 171.45 77.47)
		)
		(stroke
			(width 0)
			(type default)
		)
	)
	(wire
		(pts
			(xy 177.8 106.68) (xy 121.92 106.68)
		)
		(stroke
			(width 0)
			(type default)
		)
	)
	(wire
		(pts
			(xy 234.95 69.85) (xy 234.95 100.33)
		)
		(stroke
			(width 0)
			(type default)
		)
	)
	(bus
		(pts
			(xy 120.65 110.49) (xy 120.65 113.03)
		)
		(stroke
			(width 0)
			(type default)
		)
	)
	(wire
		(pts
			(xy 233.68 180.34) (xy 260.35 180.34)
		)
		(stroke
			(width 0)
			(type default)
		)
	)
	(bus
		(pts
			(xy 120.65 181.61) (xy 120.65 184.15)
		)
		(stroke
			(width 0)
			(type default)
		)
	)
	(wire
		(pts
			(xy 156.21 69.85) (xy 156.21 72.39)
		)
		(stroke
			(width 0)
			(type default)
		)
	)
	(wire
		(pts
			(xy 177.8 134.62) (xy 121.92 134.62)
		)
		(stroke
			(width 0)
			(type default)
		)
	)
	(wire
		(pts
			(xy 271.78 69.85) (xy 264.16 69.85)
		)
		(stroke
			(width 0)
			(type default)
		)
	)
	(wire
		(pts
			(xy 177.8 142.24) (xy 121.92 142.24)
		)
		(stroke
			(width 0)
			(type default)
		)
	)
	(bus
		(pts
			(xy 156.21 217.17) (xy 156.21 222.25)
		)
		(stroke
			(width 0)
			(type default)
		)
	)
	(wire
		(pts
			(xy 233.68 114.3) (xy 247.65 114.3)
		)
		(stroke
			(width 0)
			(type default)
		)
	)
	(bus
		(pts
			(xy 156.21 168.91) (xy 156.21 194.31)
		)
		(stroke
			(width 0)
			(type default)
		)
	)
	(wire
		(pts
			(xy 233.68 160.02) (xy 247.65 160.02)
		)
		(stroke
			(width 0)
			(type default)
		)
	)
	(wire
		(pts
			(xy 233.68 205.74) (xy 284.48 205.74)
		)
		(stroke
			(width 0)
			(type default)
		)
	)
	(bus
		(pts
			(xy 120.65 102.87) (xy 120.65 105.41)
		)
		(stroke
			(width 0)
			(type default)
		)
	)
	(wire
		(pts
			(xy 106.68 144.78) (xy 115.57 144.78)
		)
		(stroke
			(width 0)
			(type default)
		)
	)
	(wire
		(pts
			(xy 177.8 182.88) (xy 121.92 182.88)
		)
		(stroke
			(width 0)
			(type default)
		)
	)
	(wire
		(pts
			(xy 157.48 223.52) (xy 177.8 223.52)
		)
		(stroke
			(width 0)
			(type default)
		)
	)
	(bus
		(pts
			(xy 334.01 106.68) (xy 335.28 105.41)
		)
		(stroke
			(width 0)
			(type default)
		)
	)
	(wire
		(pts
			(xy 233.68 109.22) (xy 311.15 109.22)
		)
		(stroke
			(width 0)
			(type default)
		)
	)
	(wire
		(pts
			(xy 287.02 77.47) (xy 287.02 80.01)
		)
		(stroke
			(width 0)
			(type default)
		)
	)
	(wire
		(pts
			(xy 115.57 187.96) (xy 92.71 187.96)
		)
		(stroke
			(width 0)
			(type default)
		)
	)
	(wire
		(pts
			(xy 248.92 80.01) (xy 256.54 80.01)
		)
		(stroke
			(width 0)
			(type default)
		)
	)
	(wire
		(pts
			(xy 233.68 127) (xy 247.65 127)
		)
		(stroke
			(width 0)
			(type default)
		)
	)
	(wire
		(pts
			(xy 264.16 72.39) (xy 264.16 69.85)
		)
		(stroke
			(width 0)
			(type default)
		)
	)
	(wire
		(pts
			(xy 290.83 69.85) (xy 287.02 69.85)
		)
		(stroke
			(width 0)
			(type default)
		)
	)
	(bus
		(pts
			(xy 262.89 161.29) (xy 262.89 171.45)
		)
		(stroke
			(width 0)
			(type default)
		)
	)
	(bus
		(pts
			(xy 118.11 99.06) (xy 119.38 99.06)
		)
		(stroke
			(width 0)
			(type default)
		)
	)
	(wire
		(pts
			(xy 233.68 137.16) (xy 247.65 137.16)
		)
		(stroke
			(width 0)
			(type default)
		)
	)
	(bus
		(pts
			(xy 120.65 168.91) (xy 120.65 171.45)
		)
		(stroke
			(width 0)
			(type default)
		)
	)
	(bus
		(pts
			(xy 260.35 226.06) (xy 261.62 226.06)
		)
		(stroke
			(width 0)
			(type default)
		)
	)
	(bus
		(pts
			(xy 120.65 138.43) (xy 120.65 140.97)
		)
		(stroke
			(width 0)
			(type default)
		)
	)
	(wire
		(pts
			(xy 163.83 80.01) (xy 156.21 80.01)
		)
		(stroke
			(width 0)
			(type default)
		)
	)
	(wire
		(pts
			(xy 233.68 208.28) (xy 265.43 208.28)
		)
		(stroke
			(width 0)
			(type default)
		)
	)
	(wire
		(pts
			(xy 233.68 116.84) (xy 311.15 116.84)
		)
		(stroke
			(width 0)
			(type default)
		)
	)
	(wire
		(pts
			(xy 279.4 80.01) (xy 279.4 77.47)
		)
		(stroke
			(width 0)
			(type default)
		)
	)
	(wire
		(pts
			(xy 177.8 152.4) (xy 121.92 152.4)
		)
		(stroke
			(width 0)
			(type default)
		)
	)
	(wire
		(pts
			(xy 177.8 185.42) (xy 121.92 185.42)
		)
		(stroke
			(width 0)
			(type default)
		)
	)
	(wire
		(pts
			(xy 177.8 144.78) (xy 121.92 144.78)
		)
		(stroke
			(width 0)
			(type default)
		)
	)
	(bus
		(pts
			(xy 248.92 133.35) (xy 248.92 135.89)
		)
		(stroke
			(width 0)
			(type default)
		)
	)
	(wire
		(pts
			(xy 133.35 69.85) (xy 133.35 72.39)
		)
		(stroke
			(width 0)
			(type default)
		)
	)
	(bus
		(pts
			(xy 262.89 97.79) (xy 262.89 161.29)
		)
		(stroke
			(width 0)
			(type default)
		)
	)
	(bus
		(pts
			(xy 120.65 173.99) (xy 120.65 176.53)
		)
		(stroke
			(width 0)
			(type default)
		)
	)
	(wire
		(pts
			(xy 177.8 210.82) (xy 121.92 210.82)
		)
		(stroke
			(width 0)
			(type default)
		)
	)
	(bus
		(pts
			(xy 285.75 173.99) (xy 285.75 186.69)
		)
		(stroke
			(width 0)
			(type default)
		)
	)
	(bus
		(pts
			(xy 156.21 204.47) (xy 156.21 207.01)
		)
		(stroke
			(width 0)
			(type default)
		)
	)
	(wire
		(pts
			(xy 233.68 111.76) (xy 284.48 111.76)
		)
		(stroke
			(width 0)
			(type default)
		)
	)
	(wire
		(pts
			(xy 133.35 80.01) (xy 140.97 80.01)
		)
		(stroke
			(width 0)
			(type default)
		)
	)
	(bus
		(pts
			(xy 120.65 118.11) (xy 120.65 120.65)
		)
		(stroke
			(width 0)
			(type default)
		)
	)
	(bus
		(pts
			(xy 248.92 153.67) (xy 248.92 151.13)
		)
		(stroke
			(width 0)
			(type default)
		)
	)
	(bus
		(pts
			(xy 267.97 96.52) (xy 264.16 96.52)
		)
		(stroke
			(width 0)
			(type default)
		)
	)
	(wire
		(pts
			(xy 233.68 190.5) (xy 284.48 190.5)
		)
		(stroke
			(width 0)
			(type default)
		)
	)
	(bus
		(pts
			(xy 264.16 96.52) (xy 262.89 97.79)
		)
		(stroke
			(width 0)
			(type default)
		)
	)
	(bus
		(pts
			(xy 248.92 135.89) (xy 248.92 138.43)
		)
		(stroke
			(width 0)
			(type default)
		)
	)
	(bus
		(pts
			(xy 337.82 105.41) (xy 335.28 105.41)
		)
		(stroke
			(width 0)
			(type default)
		)
	)
	(bus
		(pts
			(xy 248.92 113.03) (xy 248.92 125.73)
		)
		(stroke
			(width 0)
			(type default)
		)
	)
	(wire
		(pts
			(xy 125.73 80.01) (xy 133.35 80.01)
		)
		(stroke
			(width 0)
			(type default)
		)
	)
	(wire
		(pts
			(xy 148.59 80.01) (xy 140.97 80.01)
		)
		(stroke
			(width 0)
			(type default)
		)
	)
	(bus
		(pts
			(xy 120.65 105.41) (xy 120.65 107.95)
		)
		(stroke
			(width 0)
			(type default)
		)
	)
	(wire
		(pts
			(xy 177.8 129.54) (xy 121.92 129.54)
		)
		(stroke
			(width 0)
			(type default)
		)
	)
	(wire
		(pts
			(xy 256.54 80.01) (xy 256.54 77.47)
		)
		(stroke
			(width 0)
			(type default)
		)
	)
	(wire
		(pts
			(xy 133.35 80.01) (xy 133.35 77.47)
		)
		(stroke
			(width 0)
			(type default)
		)
	)
	(wire
		(pts
			(xy 157.48 198.12) (xy 177.8 198.12)
		)
		(stroke
			(width 0)
			(type default)
		)
	)
	(wire
		(pts
			(xy 287.02 80.01) (xy 279.4 80.01)
		)
		(stroke
			(width 0)
			(type default)
		)
	)
	(bus
		(pts
			(xy 120.65 151.13) (xy 120.65 153.67)
		)
		(stroke
			(width 0)
			(type default)
		)
	)
	(bus
		(pts
			(xy 120.65 125.73) (xy 120.65 128.27)
		)
		(stroke
			(width 0)
			(type default)
		)
	)
	(bus
		(pts
			(xy 120.65 143.51) (xy 120.65 146.05)
		)
		(stroke
			(width 0)
			(type default)
		)
	)
	(wire
		(pts
			(xy 177.8 175.26) (xy 121.92 175.26)
		)
		(stroke
			(width 0)
			(type default)
		)
	)
	(bus
		(pts
			(xy 120.65 148.59) (xy 120.65 151.13)
		)
		(stroke
			(width 0)
			(type default)
		)
	)
	(bus
		(pts
			(xy 120.65 100.33) (xy 119.38 99.06)
		)
		(stroke
			(width 0)
			(type default)
		)
	)
	(wire
		(pts
			(xy 279.4 69.85) (xy 279.4 72.39)
		)
		(stroke
			(width 0)
			(type default)
		)
	)
	(wire
		(pts
			(xy 177.8 119.38) (xy 121.92 119.38)
		)
		(stroke
			(width 0)
			(type default)
		)
	)
	(bus
		(pts
			(xy 285.75 189.23) (xy 285.75 204.47)
		)
		(stroke
			(width 0)
			(type default)
		)
	)
	(wire
		(pts
			(xy 157.48 167.64) (xy 177.8 167.64)
		)
		(stroke
			(width 0)
			(type default)
		)
	)
	(bus
		(pts
			(xy 156.21 199.39) (xy 156.21 201.93)
		)
		(stroke
			(width 0)
			(type default)
		)
	)
	(bus
		(pts
			(xy 248.92 138.43) (xy 248.92 151.13)
		)
		(stroke
			(width 0)
			(type default)
		)
	)
	(wire
		(pts
			(xy 233.68 175.26) (xy 284.48 175.26)
		)
		(stroke
			(width 0)
			(type default)
		)
	)
	(wire
		(pts
			(xy 121.92 68.58) (xy 121.92 69.85)
		)
		(stroke
			(width 0)
			(type default)
		)
	)
	(wire
		(pts
			(xy 176.53 69.85) (xy 176.53 100.33)
		)
		(stroke
			(width 0)
			(type default)
		)
	)
	(wire
		(pts
			(xy 140.97 69.85) (xy 140.97 72.39)
		)
		(stroke
			(width 0)
			(type default)
		)
	)
	(bus
		(pts
			(xy 285.75 156.21) (xy 285.75 173.99)
		)
		(stroke
			(width 0)
			(type default)
		)
	)
	(bus
		(pts
			(xy 120.65 158.75) (xy 120.65 161.29)
		)
		(stroke
			(width 0)
			(type default)
		)
	)
	(wire
		(pts
			(xy 157.48 228.6) (xy 177.8 228.6)
		)
		(stroke
			(width 0)
			(type default)
		)
	)
	(bus
		(pts
			(xy 105.41 137.16) (xy 105.41 143.51)
		)
		(stroke
			(width 0)
			(type default)
		)
	)
	(bus
		(pts
			(xy 312.42 105.41) (xy 312.42 101.6)
		)
		(stroke
			(width 0)
			(type default)
		)
	)
	(bus
		(pts
			(xy 120.65 107.95) (xy 120.65 110.49)
		)
		(stroke
			(width 0)
			(type default)
		)
	)
	(wire
		(pts
			(xy 256.54 69.85) (xy 248.92 69.85)
		)
		(stroke
			(width 0)
			(type default)
		)
	)
	(bus
		(pts
			(xy 91.44 149.86) (xy 90.17 148.59)
		)
		(stroke
			(width 0)
			(type default)
		)
	)
	(bus
		(pts
			(xy 312.42 140.97) (xy 312.42 128.27)
		)
		(stroke
			(width 0)
			(type default)
		)
	)
	(wire
		(pts
			(xy 157.48 213.36) (xy 177.8 213.36)
		)
		(stroke
			(width 0)
			(type default)
		)
	)
	(wire
		(pts
			(xy 261.62 220.98) (xy 332.74 220.98)
		)
		(stroke
			(width 0)
			(type default)
		)
	)
	(wire
		(pts
			(xy 121.92 187.96) (xy 119.38 187.96)
		)
		(stroke
			(width 0)
			(type default)
		)
	)
	(wire
		(pts
			(xy 163.83 69.85) (xy 171.45 69.85)
		)
		(stroke
			(width 0)
			(type default)
		)
	)
	(wire
		(pts
			(xy 148.59 72.39) (xy 148.59 69.85)
		)
		(stroke
			(width 0)
			(type default)
		)
	)
	(bus
		(pts
			(xy 120.65 194.31) (xy 120.65 207.01)
		)
		(stroke
			(width 0)
			(type default)
		)
	)
	(wire
		(pts
			(xy 177.8 149.86) (xy 121.92 149.86)
		)
		(stroke
			(width 0)
			(type default)
		)
	)
	(wire
		(pts
			(xy 233.68 132.08) (xy 284.48 132.08)
		)
		(stroke
			(width 0)
			(type default)
		)
	)
	(bus
		(pts
			(xy 120.65 207.01) (xy 120.65 209.55)
		)
		(stroke
			(width 0)
			(type default)
		)
	)
	(bus
		(pts
			(xy 312.42 115.57) (xy 312.42 107.95)
		)
		(stroke
			(width 0)
			(type default)
		)
	)
	(bus
		(pts
			(xy 120.65 179.07) (xy 120.65 181.61)
		)
		(stroke
			(width 0)
			(type default)
		)
	)
	(wire
		(pts
			(xy 241.3 80.01) (xy 248.92 80.01)
		)
		(stroke
			(width 0)
			(type default)
		)
	)
	(wire
		(pts
			(xy 157.48 193.04) (xy 177.8 193.04)
		)
		(stroke
			(width 0)
			(type default)
		)
	)
	(wire
		(pts
			(xy 106.68 170.18) (xy 115.57 170.18)
		)
		(stroke
			(width 0)
			(type default)
		)
	)
	(wire
		(pts
			(xy 157.48 205.74) (xy 177.8 205.74)
		)
		(stroke
			(width 0)
			(type default)
		)
	)
	(wire
		(pts
			(xy 157.48 203.2) (xy 177.8 203.2)
		)
		(stroke
			(width 0)
			(type default)
		)
	)
	(wire
		(pts
			(xy 264.16 69.85) (xy 256.54 69.85)
		)
		(stroke
			(width 0)
			(type default)
		)
	)
	(wire
		(pts
			(xy 163.83 77.47) (xy 163.83 80.01)
		)
		(stroke
			(width 0)
			(type default)
		)
	)
	(bus
		(pts
			(xy 312.42 107.95) (xy 312.42 105.41)
		)
		(stroke
			(width 0)
			(type default)
		)
	)
	(wire
		(pts
			(xy 264.16 80.01) (xy 264.16 77.47)
		)
		(stroke
			(width 0)
			(type default)
		)
	)
	(wire
		(pts
			(xy 177.8 139.7) (xy 121.92 139.7)
		)
		(stroke
			(width 0)
			(type default)
		)
	)
	(bus
		(pts
			(xy 334.01 123.19) (xy 334.01 217.17)
		)
		(stroke
			(width 0)
			(type default)
		)
	)
	(wire
		(pts
			(xy 279.4 80.01) (xy 271.78 80.01)
		)
		(stroke
			(width 0)
			(type default)
		)
	)
	(bus
		(pts
			(xy 312.42 214.63) (xy 312.42 143.51)
		)
		(stroke
			(width 0)
			(type default)
		)
	)
	(bus
		(pts
			(xy 334.01 106.68) (xy 334.01 123.19)
		)
		(stroke
			(width 0)
			(type default)
		)
	)
	(bus
		(pts
			(xy 120.65 128.27) (xy 120.65 130.81)
		)
		(stroke
			(width 0)
			(type default)
		)
	)
	(wire
		(pts
			(xy 287.02 69.85) (xy 279.4 69.85)
		)
		(stroke
			(width 0)
			(type default)
		)
	)
	(wire
		(pts
			(xy 125.73 69.85) (xy 133.35 69.85)
		)
		(stroke
			(width 0)
			(type default)
		)
	)
	(bus
		(pts
			(xy 261.62 180.34) (xy 262.89 180.34)
		)
		(stroke
			(width 0)
			(type default)
		)
	)
	(wire
		(pts
			(xy 248.92 77.47) (xy 248.92 80.01)
		)
		(stroke
			(width 0)
			(type default)
		)
	)
	(wire
		(pts
			(xy 177.8 114.3) (xy 121.92 114.3)
		)
		(stroke
			(width 0)
			(type default)
		)
	)
	(wire
		(pts
			(xy 233.68 106.68) (xy 311.15 106.68)
		)
		(stroke
			(width 0)
			(type default)
		)
	)
	(bus
		(pts
			(xy 120.65 135.89) (xy 120.65 138.43)
		)
		(stroke
			(width 0)
			(type default)
		)
	)
	(wire
		(pts
			(xy 241.3 72.39) (xy 241.3 69.85)
		)
		(stroke
			(width 0)
			(type default)
		)
	)
	(bus
		(pts
			(xy 120.65 171.45) (xy 120.65 173.99)
		)
		(stroke
			(width 0)
			(type default)
		)
	)
	(bus
		(pts
			(xy 313.69 100.33) (xy 316.23 100.33)
		)
		(stroke
			(width 0)
			(type default)
		)
	)
	(wire
		(pts
			(xy 177.8 124.46) (xy 121.92 124.46)
		)
		(stroke
			(width 0)
			(type default)
		)
	)
	(bus
		(pts
			(xy 91.44 149.86) (xy 91.44 163.83)
		)
		(stroke
			(width 0)
			(type default)
		)
	)
	(wire
		(pts
			(xy 177.8 104.14) (xy 121.92 104.14)
		)
		(stroke
			(width 0)
			(type default)
		)
	)
	(wire
		(pts
			(xy 157.48 226.06) (xy 177.8 226.06)
		)
		(stroke
			(width 0)
			(type default)
		)
	)
	(wire
		(pts
			(xy 233.68 162.56) (xy 261.62 162.56)
		)
		(stroke
			(width 0)
			(type default)
		)
	)
	(wire
		(pts
			(xy 233.68 172.72) (xy 261.62 172.72)
		)
		(stroke
			(width 0)
			(type default)
		)
	)
	(wire
		(pts
			(xy 177.8 127) (xy 121.92 127)
		)
		(stroke
			(width 0)
			(type default)
		)
	)
	(bus
		(pts
			(xy 252.73 92.71) (xy 250.19 92.71)
		)
		(stroke
			(width 0)
			(type default)
		)
	)
	(wire
		(pts
			(xy 233.68 152.4) (xy 247.65 152.4)
		)
		(stroke
			(width 0)
			(type default)
		)
	)
	(wire
		(pts
			(xy 148.59 69.85) (xy 156.21 69.85)
		)
		(stroke
			(width 0)
			(type default)
		)
	)
	(wire
		(pts
			(xy 271.78 77.47) (xy 271.78 80.01)
		)
		(stroke
			(width 0)
			(type default)
		)
	)
	(bus
		(pts
			(xy 120.65 100.33) (xy 120.65 102.87)
		)
		(stroke
			(width 0)
			(type default)
		)
	)
	(wire
		(pts
			(xy 177.8 180.34) (xy 121.92 180.34)
		)
		(stroke
			(width 0)
			(type default)
		)
	)
	(wire
		(pts
			(xy 177.8 154.94) (xy 121.92 154.94)
		)
		(stroke
			(width 0)
			(type default)
		)
	)
	(wire
		(pts
			(xy 156.21 80.01) (xy 148.59 80.01)
		)
		(stroke
			(width 0)
			(type default)
		)
	)
	(wire
		(pts
			(xy 157.48 215.9) (xy 177.8 215.9)
		)
		(stroke
			(width 0)
			(type default)
		)
	)
	(wire
		(pts
			(xy 171.45 69.85) (xy 176.53 69.85)
		)
		(stroke
			(width 0)
			(type default)
		)
	)
	(wire
		(pts
			(xy 287.02 69.85) (xy 287.02 72.39)
		)
		(stroke
			(width 0)
			(type default)
		)
	)
	(wire
		(pts
			(xy 148.59 80.01) (xy 148.59 77.47)
		)
		(stroke
			(width 0)
			(type default)
		)
	)
	(bus
		(pts
			(xy 120.65 176.53) (xy 120.65 179.07)
		)
		(stroke
			(width 0)
			(type default)
		)
	)
	(wire
		(pts
			(xy 121.92 165.1) (xy 119.38 165.1)
		)
		(stroke
			(width 0)
			(type default)
		)
	)
	(wire
		(pts
			(xy 140.97 69.85) (xy 148.59 69.85)
		)
		(stroke
			(width 0)
			(type default)
		)
	)
	(bus
		(pts
			(xy 156.21 222.25) (xy 156.21 224.79)
		)
		(stroke
			(width 0)
			(type default)
		)
	)
	(wire
		(pts
			(xy 177.8 177.8) (xy 121.92 177.8)
		)
		(stroke
			(width 0)
			(type default)
		)
	)
	(wire
		(pts
			(xy 177.8 157.48) (xy 121.92 157.48)
		)
		(stroke
			(width 0)
			(type default)
		)
	)
	(bus
		(pts
			(xy 266.7 208.28) (xy 267.97 208.28)
		)
		(stroke
			(width 0)
			(type default)
		)
	)
	(bus
		(pts
			(xy 120.65 146.05) (xy 120.65 148.59)
		)
		(stroke
			(width 0)
			(type default)
		)
	)
	(wire
		(pts
			(xy 177.8 109.22) (xy 121.92 109.22)
		)
		(stroke
			(width 0)
			(type default)
		)
	)
	(bus
		(pts
			(xy 285.75 130.81) (xy 285.75 156.21)
		)
		(stroke
			(width 0)
			(type default)
		)
	)
	(wire
		(pts
			(xy 256.54 80.01) (xy 264.16 80.01)
		)
		(stroke
			(width 0)
			(type default)
		)
	)
	(bus
		(pts
			(xy 120.65 123.19) (xy 120.65 125.73)
		)
		(stroke
			(width 0)
			(type default)
		)
	)
	(wire
		(pts
			(xy 261.62 218.44) (xy 332.74 218.44)
		)
		(stroke
			(width 0)
			(type default)
		)
	)
	(bus
		(pts
			(xy 248.92 153.67) (xy 248.92 158.75)
		)
		(stroke
			(width 0)
			(type default)
		)
	)
	(wire
		(pts
			(xy 233.68 218.44) (xy 256.54 218.44)
		)
		(stroke
			(width 0)
			(type default)
		)
	)
	(wire
		(pts
			(xy 233.68 134.62) (xy 247.65 134.62)
		)
		(stroke
			(width 0)
			(type default)
		)
	)
	(wire
		(pts
			(xy 233.68 144.78) (xy 311.15 144.78)
		)
		(stroke
			(width 0)
			(type default)
		)
	)
	(wire
		(pts
			(xy 233.68 220.98) (xy 256.54 220.98)
		)
		(stroke
			(width 0)
			(type default)
		)
	)
	(bus
		(pts
			(xy 120.65 113.03) (xy 120.65 115.57)
		)
		(stroke
			(width 0)
			(type default)
		)
	)
	(wire
		(pts
			(xy 177.8 132.08) (xy 121.92 132.08)
		)
		(stroke
			(width 0)
			(type default)
		)
	)
	(wire
		(pts
			(xy 233.68 154.94) (xy 247.65 154.94)
		)
		(stroke
			(width 0)
			(type default)
		)
	)
	(bus
		(pts
			(xy 312.42 128.27) (xy 312.42 118.11)
		)
		(stroke
			(width 0)
			(type default)
		)
	)
	(bus
		(pts
			(xy 120.65 163.83) (xy 120.65 168.91)
		)
		(stroke
			(width 0)
			(type default)
		)
	)
	(bus
		(pts
			(xy 120.65 184.15) (xy 120.65 186.69)
		)
		(stroke
			(width 0)
			(type default)
		)
	)
	(wire
		(pts
			(xy 177.8 218.44) (xy 121.92 218.44)
		)
		(stroke
			(width 0)
			(type default)
		)
	)
	(wire
		(pts
			(xy 233.68 157.48) (xy 284.48 157.48)
		)
		(stroke
			(width 0)
			(type default)
		)
	)
	(bus
		(pts
			(xy 120.65 115.57) (xy 120.65 118.11)
		)
		(stroke
			(width 0)
			(type default)
		)
	)
	(bus
		(pts
			(xy 156.21 194.31) (xy 156.21 199.39)
		)
		(stroke
			(width 0)
			(type default)
		)
	)
	(wire
		(pts
			(xy 92.71 165.1) (xy 115.57 165.1)
		)
		(stroke
			(width 0)
			(type default)
		)
	)
	(wire
		(pts
			(xy 177.8 162.56) (xy 121.92 162.56)
		)
		(stroke
			(width 0)
			(type default)
		)
	)
	(wire
		(pts
			(xy 241.3 80.01) (xy 241.3 77.47)
		)
		(stroke
			(width 0)
			(type default)
		)
	)
	(bus
		(pts
			(xy 288.29 96.52) (xy 287.02 96.52)
		)
		(stroke
			(width 0)
			(type default)
		)
	)
	(bus
		(pts
			(xy 120.65 140.97) (xy 120.65 143.51)
		)
		(stroke
			(width 0)
			(type default)
		)
	)
	(bus
		(pts
			(xy 248.92 93.98) (xy 250.19 92.71)
		)
		(stroke
			(width 0)
			(type default)
		)
	)
	(bus
		(pts
			(xy 105.41 137.16) (xy 104.14 135.89)
		)
		(stroke
			(width 0)
			(type default)
		)
	)
	(wire
		(pts
			(xy 177.8 160.02) (xy 121.92 160.02)
		)
		(stroke
			(width 0)
			(type default)
		)
	)
	(bus
		(pts
			(xy 120.65 186.69) (xy 120.65 194.31)
		)
		(stroke
			(width 0)
			(type default)
		)
	)
	(bus
		(pts
			(xy 156.21 214.63) (xy 156.21 217.17)
		)
		(stroke
			(width 0)
			(type default)
		)
	)
	(wire
		(pts
			(xy 125.73 77.47) (xy 125.73 80.01)
		)
		(stroke
			(width 0)
			(type default)
		)
	)
	(wire
		(pts
			(xy 287.02 80.01) (xy 287.02 81.28)
		)
		(stroke
			(width 0)
			(type default)
		)
	)
	(wire
		(pts
			(xy 133.35 69.85) (xy 140.97 69.85)
		)
		(stroke
			(width 0)
			(type default)
		)
	)
	(wire
		(pts
			(xy 233.68 119.38) (xy 311.15 119.38)
		)
		(stroke
			(width 0)
			(type default)
		)
	)
	(bus
		(pts
			(xy 88.9 148.59) (xy 90.17 148.59)
		)
		(stroke
			(width 0)
			(type default)
		)
	)
	(wire
		(pts
			(xy 248.92 69.85) (xy 241.3 69.85)
		)
		(stroke
			(width 0)
			(type default)
		)
	)
	(bus
		(pts
			(xy 120.65 130.81) (xy 120.65 133.35)
		)
		(stroke
			(width 0)
			(type default)
		)
	)
	(bus
		(pts
			(xy 153.67 243.84) (xy 154.94 243.84)
		)
		(stroke
			(width 0)
			(type default)
		)
	)
	(wire
		(pts
			(xy 176.53 100.33) (xy 177.8 100.33)
		)
		(stroke
			(width 0)
			(type default)
		)
	)
	(wire
		(pts
			(xy 140.97 77.47) (xy 140.97 80.01)
		)
		(stroke
			(width 0)
			(type default)
		)
	)
	(wire
		(pts
			(xy 177.8 187.96) (xy 121.92 187.96)
		)
		(stroke
			(width 0)
			(type default)
		)
	)
	(wire
		(pts
			(xy 177.8 137.16) (xy 121.92 137.16)
		)
		(stroke
			(width 0)
			(type default)
		)
	)
	(wire
		(pts
			(xy 233.68 187.96) (xy 284.48 187.96)
		)
		(stroke
			(width 0)
			(type default)
		)
	)
	(wire
		(pts
			(xy 177.8 116.84) (xy 121.92 116.84)
		)
		(stroke
			(width 0)
			(type default)
		)
	)
	(bus
		(pts
			(xy 120.65 133.35) (xy 120.65 135.89)
		)
		(stroke
			(width 0)
			(type default)
		)
	)
	(bus
		(pts
			(xy 120.65 153.67) (xy 120.65 156.21)
		)
		(stroke
			(width 0)
			(type default)
		)
	)
	(wire
		(pts
			(xy 121.92 144.78) (xy 119.38 144.78)
		)
		(stroke
			(width 0)
			(type default)
		)
	)
	(wire
		(pts
			(xy 177.8 208.28) (xy 121.92 208.28)
		)
		(stroke
			(width 0)
			(type default)
		)
	)
	(bus
		(pts
			(xy 312.42 101.6) (xy 313.69 100.33)
		)
		(stroke
			(width 0)
			(type default)
		)
	)
	(wire
		(pts
			(xy 156.21 80.01) (xy 156.21 77.47)
		)
		(stroke
			(width 0)
			(type default)
		)
	)
	(wire
		(pts
			(xy 177.8 147.32) (xy 121.92 147.32)
		)
		(stroke
			(width 0)
			(type default)
		)
	)
	(bus
		(pts
			(xy 156.21 229.87) (xy 156.21 227.33)
		)
		(stroke
			(width 0)
			(type default)
		)
	)
	(wire
		(pts
			(xy 256.54 69.85) (xy 256.54 72.39)
		)
		(stroke
			(width 0)
			(type default)
		)
	)
	(bus
		(pts
			(xy 105.41 143.51) (xy 105.41 168.91)
		)
		(stroke
			(width 0)
			(type default)
		)
	)
	(bus
		(pts
			(xy 285.75 110.49) (xy 285.75 120.65)
		)
		(stroke
			(width 0)
			(type default)
		)
	)
	(bus
		(pts
			(xy 120.65 120.65) (xy 120.65 123.19)
		)
		(stroke
			(width 0)
			(type default)
		)
	)
	(bus
		(pts
			(xy 120.65 156.21) (xy 120.65 158.75)
		)
		(stroke
			(width 0)
			(type default)
		)
	)
	(bus
		(pts
			(xy 120.65 161.29) (xy 120.65 163.83)
		)
		(stroke
			(width 0)
			(type default)
		)
	)
	(bus
		(pts
			(xy 334.01 217.17) (xy 334.01 219.71)
		)
		(stroke
			(width 0)
			(type default)
		)
	)
	(wire
		(pts
			(xy 279.4 69.85) (xy 271.78 69.85)
		)
		(stroke
			(width 0)
			(type default)
		)
	)
	(wire
		(pts
			(xy 121.92 69.85) (xy 125.73 69.85)
		)
		(stroke
			(width 0)
			(type default)
		)
	)
	(wire
		(pts
			(xy 233.68 215.9) (xy 311.15 215.9)
		)
		(stroke
			(width 0)
			(type default)
		)
	)
	(bus
		(pts
			(xy 285.75 97.79) (xy 285.75 110.49)
		)
		(stroke
			(width 0)
			(type default)
		)
	)
	(wire
		(pts
			(xy 125.73 69.85) (xy 125.73 72.39)
		)
		(stroke
			(width 0)
			(type default)
		)
	)
	(wire
		(pts
			(xy 241.3 69.85) (xy 234.95 69.85)
		)
		(stroke
			(width 0)
			(type default)
		)
	)
	(wire
		(pts
			(xy 233.68 121.92) (xy 284.48 121.92)
		)
		(stroke
			(width 0)
			(type default)
		)
	)
	(bus
		(pts
			(xy 248.92 125.73) (xy 248.92 133.35)
		)
		(stroke
			(width 0)
			(type default)
		)
	)
	(wire
		(pts
			(xy 177.8 172.72) (xy 121.92 172.72)
		)
		(stroke
			(width 0)
			(type default)
		)
	)
	(bus
		(pts
			(xy 285.75 97.79) (xy 287.02 96.52)
		)
		(stroke
			(width 0)
			(type default)
		)
	)
	(wire
		(pts
			(xy 157.48 200.66) (xy 177.8 200.66)
		)
		(stroke
			(width 0)
			(type default)
		)
	)
	(wire
		(pts
			(xy 233.68 129.54) (xy 311.15 129.54)
		)
		(stroke
			(width 0)
			(type default)
		)
	)
	(bus
		(pts
			(xy 91.44 163.83) (xy 91.44 186.69)
		)
		(stroke
			(width 0)
			(type default)
		)
	)
	(bus
		(pts
			(xy 312.42 118.11) (xy 312.42 115.57)
		)
		(stroke
			(width 0)
			(type default)
		)
	)
	(wire
		(pts
			(xy 264.16 80.01) (xy 271.78 80.01)
		)
		(stroke
			(width 0)
			(type default)
		)
	)
	(wire
		(pts
			(xy 290.83 68.58) (xy 290.83 69.85)
		)
		(stroke
			(width 0)
			(type default)
		)
	)
	(wire
		(pts
			(xy 163.83 69.85) (xy 163.83 72.39)
		)
		(stroke
			(width 0)
			(type default)
		)
	)
	(bus
		(pts
			(xy 285.75 120.65) (xy 285.75 130.81)
		)
		(stroke
			(width 0)
			(type default)
		)
	)
	(wire
		(pts
			(xy 233.68 228.6) (xy 236.22 228.6)
		)
		(stroke
			(width 0)
			(type default)
		)
	)
	(wire
		(pts
			(xy 125.73 80.01) (xy 125.73 81.28)
		)
		(stroke
			(width 0)
			(type default)
		)
	)
	(bus
		(pts
			(xy 345.44 147.32) (xy 346.71 147.32)
		)
		(stroke
			(width 0)
			(type default)
		)
	)
	(bus
		(pts
			(xy 285.75 189.23) (xy 285.75 186.69)
		)
		(stroke
			(width 0)
			(type default)
		)
	)
	(wire
		(pts
			(xy 177.8 170.18) (xy 121.92 170.18)
		)
		(stroke
			(width 0)
			(type default)
		)
	)
	(wire
		(pts
			(xy 233.68 139.7) (xy 247.65 139.7)
		)
		(stroke
			(width 0)
			(type default)
		)
	)
	(wire
		(pts
			(xy 233.68 147.32) (xy 344.17 147.32)
		)
		(stroke
			(width 0)
			(type default)
		)
	)
	(wire
		(pts
			(xy 177.8 165.1) (xy 121.92 165.1)
		)
		(stroke
			(width 0)
			(type default)
		)
	)
	(wire
		(pts
			(xy 233.68 142.24) (xy 311.15 142.24)
		)
		(stroke
			(width 0)
			(type default)
		)
	)
	(wire
		(pts
			(xy 171.45 72.39) (xy 171.45 69.85)
		)
		(stroke
			(width 0)
			(type default)
		)
	)
	(wire
		(pts
			(xy 271.78 69.85) (xy 271.78 72.39)
		)
		(stroke
			(width 0)
			(type default)
		)
	)
	(wire
		(pts
			(xy 121.92 170.18) (xy 119.38 170.18)
		)
		(stroke
			(width 0)
			(type default)
		)
	)
	(bus
		(pts
			(xy 248.92 93.98) (xy 248.92 113.03)
		)
		(stroke
			(width 0)
			(type default)
		)
	)
	(wire
		(pts
			(xy 248.92 69.85) (xy 248.92 72.39)
		)
		(stroke
			(width 0)
			(type default)
		)
	)
	(bus
		(pts
			(xy 156.21 242.57) (xy 156.21 229.87)
		)
		(stroke
			(width 0)
			(type default)
		)
	)
	(bus
		(pts
			(xy 120.65 209.55) (xy 120.65 217.17)
		)
		(stroke
			(width 0)
			(type default)
		)
	)
	(bus
		(pts
			(xy 312.42 143.51) (xy 312.42 140.97)
		)
		(stroke
			(width 0)
			(type default)
		)
	)
	(bus
		(pts
			(xy 156.21 207.01) (xy 156.21 214.63)
		)
		(stroke
			(width 0)
			(type default)
		)
	)
	(bus
		(pts
			(xy 104.14 135.89) (xy 101.6 135.89)
		)
		(stroke
			(width 0)
			(type default)
		)
	)
	(wire
		(pts
			(xy 233.68 124.46) (xy 332.74 124.46)
		)
		(stroke
			(width 0)
			(type default)
		)
	)
	(wire
		(pts
			(xy 156.21 69.85) (xy 163.83 69.85)
		)
		(stroke
			(width 0)
			(type default)
		)
	)
	(wire
		(pts
			(xy 233.68 100.33) (xy 234.95 100.33)
		)
		(stroke
			(width 0)
			(type default)
		)
	)
	(wire
		(pts
			(xy 177.8 111.76) (xy 121.92 111.76)
		)
		(stroke
			(width 0)
			(type default)
		)
	)
	(bus
		(pts
			(xy 156.21 201.93) (xy 156.21 204.47)
		)
		(stroke
			(width 0)
			(type default)
		)
	)
	(bus
		(pts
			(xy 156.21 224.79) (xy 156.21 227.33)
		)
		(stroke
			(width 0)
			(type default)
		)
	)
	(bus
		(pts
			(xy 154.94 243.84) (xy 156.21 242.57)
		)
		(stroke
			(width 0)
			(type default)
		)
	)
	(wire
		(pts
			(xy 177.8 195.58) (xy 121.92 195.58)
		)
		(stroke
			(width 0)
			(type default)
		)
	)
	(label "PMOD_B.IO10"
		(at 234.95 134.62 0)
		(effects
			(font
				(size 1.27 1.27)
			)
			(justify left bottom)
		)
	)
	(label "UART0.TX"
		(at 102.87 187.96 180)
		(effects
			(font
				(size 1.27 1.27)
			)
			(justify right bottom)
		)
	)
	(label "CW_HEADER.TPDID"
		(at 176.53 213.36 180)
		(effects
			(font
				(size 1.27 1.27)
			)
			(justify right bottom)
		)
	)
	(label "SUP_MCU.A17"
		(at 149.86 132.08 180)
		(effects
			(font
				(size 1.27 1.27)
			)
			(justify right bottom)
		)
	)
	(label "PMOD_A.IO3"
		(at 271.78 175.26 0)
		(effects
			(font
				(size 1.27 1.27)
			)
			(justify left bottom)
		)
	)
	(label "SUP_MCU.A9"
		(at 149.86 139.7 180)
		(effects
			(font
				(size 1.27 1.27)
			)
			(justify right bottom)
		)
	)
	(label "CW_HEADER.MISO"
		(at 176.53 200.66 180)
		(effects
			(font
				(size 1.27 1.27)
			)
			(justify right bottom)
		)
	)
	(label "SUP_MCU.A3"
		(at 149.86 210.82 180)
		(effects
			(font
				(size 1.27 1.27)
			)
			(justify right bottom)
		)
	)
	(label "PMOD_A.IO9"
		(at 271.78 157.48 0)
		(effects
			(font
				(size 1.27 1.27)
			)
			(justify left bottom)
		)
	)
	(label "~{PB_CTRL_INT}"
		(at 236.22 220.98 0)
		(effects
			(font
				(size 1.27 1.27)
			)
			(justify left bottom)
		)
	)
	(label "USER_IO.LED_BLUE"
		(at 289.56 129.54 0)
		(effects
			(font
				(size 1.27 1.27)
			)
			(justify left bottom)
		)
	)
	(label "PMOD_A.IO1"
		(at 271.78 205.74 0)
		(effects
			(font
				(size 1.27 1.27)
			)
			(justify left bottom)
		)
	)
	(label "PB_CTRL.~{PB_CTRL_CLR}"
		(at 270.51 218.44 0)
		(effects
			(font
				(size 1.27 1.27)
			)
			(justify left bottom)
		)
	)
	(label "PLL.CLK1"
		(at 252.73 172.72 0)
		(effects
			(font
				(size 1.27 1.27)
			)
			(justify left bottom)
		)
	)
	(label "SUP_MCU.A7"
		(at 149.86 182.88 180)
		(effects
			(font
				(size 1.27 1.27)
			)
			(justify right bottom)
		)
	)
	(label "PMOD_B.IO9"
		(at 234.95 139.7 0)
		(effects
			(font
				(size 1.27 1.27)
			)
			(justify left bottom)
		)
	)
	(label "SUP_MCU.TX0"
		(at 149.86 165.1 180)
		(effects
			(font
				(size 1.27 1.27)
			)
			(justify right bottom)
		)
	)
	(label "USB_USER.VBUS_PEN"
		(at 289.56 147.32 0)
		(effects
			(font
				(size 1.27 1.27)
			)
			(justify left bottom)
		)
	)
	(label "USER_IO.LED_GREEN5"
		(at 289.56 106.68 0)
		(effects
			(font
				(size 1.27 1.27)
			)
			(justify left bottom)
		)
	)
	(label "~{PB_CTRL_CLR}"
		(at 236.22 218.44 0)
		(effects
			(font
				(size 1.27 1.27)
			)
			(justify left bottom)
		)
	)
	(label "USER_IO.LED_RED"
		(at 289.56 116.84 0)
		(effects
			(font
				(size 1.27 1.27)
			)
			(justify left bottom)
		)
	)
	(label "CW_HEADER.HS2"
		(at 176.53 167.64 180)
		(effects
			(font
				(size 1.27 1.27)
			)
			(justify right bottom)
		)
	)
	(label "SUP_MCU.A4"
		(at 149.86 160.02 180)
		(effects
			(font
				(size 1.27 1.27)
			)
			(justify right bottom)
		)
	)
	(label "SUP_MCU.D5"
		(at 149.86 129.54 180)
		(effects
			(font
				(size 1.27 1.27)
			)
			(justify right bottom)
		)
	)
	(label "CW_HEADER.IO3"
		(at 176.53 215.9 180)
		(effects
			(font
				(size 1.27 1.27)
			)
			(justify right bottom)
		)
	)
	(label "SUP_MCU.TX1"
		(at 149.86 144.78 180)
		(effects
			(font
				(size 1.27 1.27)
			)
			(justify right bottom)
		)
	)
	(label "SUP_MCU.CLKO"
		(at 149.86 162.56 180)
		(effects
			(font
				(size 1.27 1.27)
			)
			(justify right bottom)
		)
	)
	(label "SUP_MCU.ALE"
		(at 149.86 152.4 180)
		(effects
			(font
				(size 1.27 1.27)
			)
			(justify right bottom)
		)
	)
	(label "SUP_MCU.A2"
		(at 149.86 218.44 180)
		(effects
			(font
				(size 1.27 1.27)
			)
			(justify right bottom)
		)
	)
	(label "CW_HEADER.RST"
		(at 176.53 228.6 180)
		(effects
			(font
				(size 1.27 1.27)
			)
			(justify right bottom)
		)
	)
	(label "USER_IO.LED_GREEN1"
		(at 289.56 215.9 0)
		(effects
			(font
				(size 1.27 1.27)
			)
			(justify left bottom)
		)
	)
	(label "SUP_MCU.D4"
		(at 149.86 124.46 180)
		(effects
			(font
				(size 1.27 1.27)
			)
			(justify right bottom)
		)
	)
	(label "UART0.RX"
		(at 102.87 165.1 180)
		(effects
			(font
				(size 1.27 1.27)
			)
			(justify right bottom)
		)
	)
	(label "SUP_MCU.D1"
		(at 149.86 121.92 180)
		(effects
			(font
				(size 1.27 1.27)
			)
			(justify right bottom)
		)
	)
	(label "SUP_MCU.A5"
		(at 149.86 175.26 180)
		(effects
			(font
				(size 1.27 1.27)
			)
			(justify right bottom)
		)
	)
	(label "PLL.CLK2"
		(at 252.73 162.56 0)
		(effects
			(font
				(size 1.27 1.27)
			)
			(justify left bottom)
		)
	)
	(label "PMOD_A.IO10"
		(at 271.78 190.5 0)
		(effects
			(font
				(size 1.27 1.27)
			)
			(justify left bottom)
		)
	)
	(label "SUP_MCU.A10"
		(at 149.86 142.24 180)
		(effects
			(font
				(size 1.27 1.27)
			)
			(justify right bottom)
		)
	)
	(label "SUP_MCU.A1"
		(at 149.86 208.28 180)
		(effects
			(font
				(size 1.27 1.27)
			)
			(justify right bottom)
		)
	)
	(label "SUP_MCU.D6"
		(at 149.86 127 180)
		(effects
			(font
				(size 1.27 1.27)
			)
			(justify right bottom)
		)
	)
	(label "SUP_MCU.A6"
		(at 149.86 185.42 180)
		(effects
			(font
				(size 1.27 1.27)
			)
			(justify right bottom)
		)
	)
	(label "SUP_MCU.A13"
		(at 149.86 111.76 180)
		(effects
			(font
				(size 1.27 1.27)
			)
			(justify right bottom)
		)
	)
	(label "SUP_MCU.A8"
		(at 149.86 147.32 180)
		(effects
			(font
				(size 1.27 1.27)
			)
			(justify right bottom)
		)
	)
	(label "SUP_MCU.A14"
		(at 149.86 106.68 180)
		(effects
			(font
				(size 1.27 1.27)
			)
			(justify right bottom)
		)
	)
	(label "USB_HOST.VBUS_PEN"
		(at 241.3 208.28 0)
		(effects
			(font
				(size 1.27 1.27)
			)
			(justify left bottom)
		)
	)
	(label "SUP_MCU.RD"
		(at 149.86 172.72 180)
		(effects
			(font
				(size 1.27 1.27)
			)
			(justify right bottom)
		)
	)
	(label "SUP_MCU.RX0"
		(at 149.86 187.96 180)
		(effects
			(font
				(size 1.27 1.27)
			)
			(justify right bottom)
		)
	)
	(label "SUP_MCU.D2"
		(at 149.86 195.58 180)
		(effects
			(font
				(size 1.27 1.27)
			)
			(justify right bottom)
		)
	)
	(label "USER_IO.LED_GREEN4"
		(at 289.56 144.78 0)
		(effects
			(font
				(size 1.27 1.27)
			)
			(justify left bottom)
		)
	)
	(label "PMOD_A.IO4"
		(at 271.78 187.96 0)
		(effects
			(font
				(size 1.27 1.27)
			)
			(justify left bottom)
		)
	)
	(label "SUP_MCU.RX1"
		(at 149.86 170.18 180)
		(effects
			(font
				(size 1.27 1.27)
			)
			(justify right bottom)
		)
	)
	(label "SUP_MCU.SPARE0"
		(at 237.49 180.34 0)
		(effects
			(font
				(size 1.27 1.27)
			)
			(justify left bottom)
		)
	)
	(label "SUP_MCU.A18"
		(at 149.86 134.62 180)
		(effects
			(font
				(size 1.27 1.27)
			)
			(justify right bottom)
		)
	)
	(label "USER_IO.LED_GREEN0"
		(at 289.56 142.24 0)
		(effects
			(font
				(size 1.27 1.27)
			)
			(justify left bottom)
		)
	)
	(label "PB_CTRL.VDDR_EN"
		(at 314.96 124.46 0)
		(effects
			(font
				(size 1.27 1.27)
			)
			(justify left bottom)
		)
	)
	(label "CW_HEADER.IO1"
		(at 176.53 220.98 180)
		(effects
			(font
				(size 1.27 1.27)
			)
			(justify right bottom)
		)
	)
	(label "SUP_MCU.A16"
		(at 149.86 104.14 180)
		(effects
			(font
				(size 1.27 1.27)
			)
			(justify right bottom)
		)
	)
	(label "PMOD_B.IO3"
		(at 234.95 137.16 0)
		(effects
			(font
				(size 1.27 1.27)
			)
			(justify left bottom)
		)
	)
	(label "CW_HEADER.MOSI"
		(at 176.53 226.06 180)
		(effects
			(font
				(size 1.27 1.27)
			)
			(justify right bottom)
		)
	)
	(label "CW_HEADER.TPDIC"
		(at 176.53 198.12 180)
		(effects
			(font
				(size 1.27 1.27)
			)
			(justify right bottom)
		)
	)
	(label "PMOD_A.IO7"
		(at 271.78 132.08 0)
		(effects
			(font
				(size 1.27 1.27)
			)
			(justify left bottom)
		)
	)
	(label "SUP_MCU.A12"
		(at 149.86 180.34 180)
		(effects
			(font
				(size 1.27 1.27)
			)
			(justify right bottom)
		)
	)
	(label "SUP_MCU.D0"
		(at 149.86 114.3 180)
		(effects
			(font
				(size 1.27 1.27)
			)
			(justify right bottom)
		)
	)
	(label "SUP_MCU.A0"
		(at 149.86 149.86 180)
		(effects
			(font
				(size 1.27 1.27)
			)
			(justify right bottom)
		)
	)
	(label "USB_USER.VDET"
		(at 242.57 226.06 0)
		(effects
			(font
				(size 1.27 1.27)
			)
			(justify left bottom)
		)
	)
	(label "USER_IO.LED_GREEN2"
		(at 289.56 119.38 0)
		(effects
			(font
				(size 1.27 1.27)
			)
			(justify left bottom)
		)
	)
	(label "UART1.TX"
		(at 115.57 170.18 180)
		(effects
			(font
				(size 1.27 1.27)
			)
			(justify right bottom)
		)
	)
	(label "SUP_MCU.D7"
		(at 149.86 154.94 180)
		(effects
			(font
				(size 1.27 1.27)
			)
			(justify right bottom)
		)
	)
	(label "CW_HEADER.IO4"
		(at 176.53 203.2 180)
		(effects
			(font
				(size 1.27 1.27)
			)
			(justify right bottom)
		)
	)
	(label "PB_CTRL.~{PB_CTRL_INT}"
		(at 270.51 220.98 0)
		(effects
			(font
				(size 1.27 1.27)
			)
			(justify left bottom)
		)
	)
	(label "PMOD_B.IO7"
		(at 234.95 160.02 0)
		(effects
			(font
				(size 1.27 1.27)
			)
			(justify left bottom)
		)
	)
	(label "PMOD_B.IO2"
		(at 234.95 152.4 0)
		(effects
			(font
				(size 1.27 1.27)
			)
			(justify left bottom)
		)
	)
	(label "CW_HEADER.HS1"
		(at 176.53 193.04 180)
		(effects
			(font
				(size 1.27 1.27)
			)
			(justify right bottom)
		)
	)
	(label "PMOD_A.IO2"
		(at 271.78 111.76 0)
		(effects
			(font
				(size 1.27 1.27)
			)
			(justify left bottom)
		)
	)
	(label "SUP_MCU.WR"
		(at 149.86 137.16 180)
		(effects
			(font
				(size 1.27 1.27)
			)
			(justify right bottom)
		)
	)
	(label "PMOD_A.IO8"
		(at 271.78 121.92 0)
		(effects
			(font
				(size 1.27 1.27)
			)
			(justify left bottom)
		)
	)
	(label "UART1.RX"
		(at 115.57 144.78 180)
		(effects
			(font
				(size 1.27 1.27)
			)
			(justify right bottom)
		)
	)
	(label "CW_HEADER.IO2"
		(at 176.53 205.74 180)
		(effects
			(font
				(size 1.27 1.27)
			)
			(justify right bottom)
		)
	)
	(label "SUP_MCU.A19"
		(at 149.86 177.8 180)
		(effects
			(font
				(size 1.27 1.27)
			)
			(justify right bottom)
		)
	)
	(label "PMOD_B.IO8"
		(at 234.95 127 0)
		(effects
			(font
				(size 1.27 1.27)
			)
			(justify left bottom)
		)
	)
	(label "CW_HEADER.TSCK"
		(at 176.53 223.52 180)
		(effects
			(font
				(size 1.27 1.27)
			)
			(justify right bottom)
		)
	)
	(label "SUP_MCU.CE"
		(at 149.86 157.48 180)
		(effects
			(font
				(size 1.27 1.27)
			)
			(justify right bottom)
		)
	)
	(label "USER_IO.LED_GREEN3"
		(at 289.56 109.22 0)
		(effects
			(font
				(size 1.27 1.27)
			)
			(justify left bottom)
		)
	)
	(label "PMOD_B.IO1"
		(at 234.95 154.94 0)
		(effects
			(font
				(size 1.27 1.27)
			)
			(justify left bottom)
		)
	)
	(label "SUP_MCU.D3"
		(at 149.86 119.38 180)
		(effects
			(font
				(size 1.27 1.27)
			)
			(justify right bottom)
		)
	)
	(label "PMOD_B.IO4"
		(at 234.95 114.3 0)
		(effects
			(font
				(size 1.27 1.27)
			)
			(justify left bottom)
		)
	)
	(label "SUP_MCU.A11"
		(at 149.86 116.84 180)
		(effects
			(font
				(size 1.27 1.27)
			)
			(justify right bottom)
		)
	)
	(label "SUP_MCU.A15"
		(at 149.86 109.22 180)
		(effects
			(font
				(size 1.27 1.27)
			)
			(justify right bottom)
		)
	)
	(hierarchical_label "USB_HOST{SPI-USB}"
		(shape bidirectional)
		(at 267.97 208.28 0)
		(effects
			(font
				(size 1.27 1.27)
			)
			(justify left)
		)
	)
	(hierarchical_label "FAN_PWM_CTRL"
		(shape output)
		(at 236.22 228.6 0)
		(effects
			(font
				(size 1.27 1.27)
			)
			(justify left)
		)
	)
	(hierarchical_label "USER_IO{USER-IO}"
		(shape bidirectional)
		(at 316.23 100.33 0)
		(effects
			(font
				(size 1.27 1.27)
			)
			(justify left)
		)
	)
	(hierarchical_label "PMOD_A{PMOD}"
		(shape bidirectional)
		(at 288.29 96.52 0)
		(effects
			(font
				(size 1.27 1.27)
			)
			(justify left)
		)
	)
	(hierarchical_label "PLL{PLL-CLK}"
		(shape output)
		(at 267.97 96.52 0)
		(effects
			(font
				(size 1.27 1.27)
			)
			(justify left)
		)
	)
	(hierarchical_label "SUP_MCU{SUP-MCU}"
		(shape bidirectional)
		(at 118.11 99.06 180)
		(effects
			(font
				(size 1.27 1.27)
			)
			(justify right)
		)
	)
	(hierarchical_label "CW_HEADER{CW-20PIN}"
		(shape bidirectional)
		(at 153.67 243.84 180)
		(effects
			(font
				(size 1.27 1.27)
			)
			(justify right)
		)
	)
	(hierarchical_label "PB_CTRL{PB-CTRL}"
		(shape bidirectional)
		(at 337.82 105.41 0)
		(effects
			(font
				(size 1.27 1.27)
			)
			(justify left)
		)
	)
	(hierarchical_label "USB_USER{USB-FPGA-PHY}"
		(shape bidirectional)
		(at 346.71 147.32 0)
		(effects
			(font
				(size 1.27 1.27)
			)
			(justify left)
		)
	)
	(hierarchical_label "SUP_MCU{SUP-MCU}"
		(shape bidirectional)
		(at 262.89 180.34 0)
		(effects
			(font
				(size 1.27 1.27)
			)
			(justify left)
		)
	)
	(hierarchical_label "PMOD_B{PMOD}"
		(shape bidirectional)
		(at 252.73 92.71 0)
		(effects
			(font
				(size 1.27 1.27)
			)
			(justify left)
		)
	)
	(hierarchical_label "UART0{UART}"
		(shape input)
		(at 88.9 148.59 180)
		(effects
			(font
				(size 1.27 1.27)
			)
			(justify right)
		)
	)
	(hierarchical_label "USB_USER{USB-FPGA-PHY}"
		(shape bidirectional)
		(at 261.62 226.06 0)
		(effects
			(font
				(size 1.27 1.27)
			)
			(justify left)
		)
	)
	(hierarchical_label "UART1{UART}"
		(shape input)
		(at 101.6 135.89 180)
		(effects
			(font
				(size 1.27 1.27)
			)
			(justify right)
		)
	)
	(symbol
		(lib_id "antmicropower:GND")
		(at 125.73 81.28 0)
		(unit 1)
		(exclude_from_sim no)
		(in_bom yes)
		(on_board yes)
		(dnp no)
		(property "Reference" "#PWR08"
			(at 125.73 87.63 0)
			(effects
				(font
					(size 1.27 1.27)
				)
				(hide yes)
			)
		)
		(property "Value" "GND"
			(at 125.73 85.09 0)
			(effects
				(font
					(size 1.27 1.27)
				)
			)
		)
		(property "Footprint" ""
			(at 134.62 88.9 0)
			(effects
				(font
					(size 1.27 1.27)
					(thickness 0.15)
				)
				(justify left bottom)
				(hide yes)
			)
		)
		(property "Datasheet" ""
			(at 134.62 93.98 0)
			(effects
				(font
					(size 1.27 1.27)
					(thickness 0.15)
				)
				(justify left bottom)
				(hide yes)
			)
		)
		(property "Description" ""
			(at 125.73 81.28 0)
			(effects
				(font
					(size 1.27 1.27)
				)
			)
		)
		(property "Author" "Antmicro"
			(at 134.62 88.9 0)
			(effects
				(font
					(size 1.27 1.27)
					(thickness 0.15)
				)
				(justify left bottom)
				(hide yes)
			)
		)
		(property "License" "Apache-2.0"
			(at 134.62 91.44 0)
			(effects
				(font
					(size 1.27 1.27)
					(thickness 0.15)
				)
				(justify left bottom)
				(hide yes)
			)
		)
		(pin "1"
		)
		(instances
			(project "k410t-devboard"
				(path ""
					(reference "#PWR08")
					(unit 1)
				)
			)
		)
	)
	(symbol
		(lib_id "k410t-devboard:Net-Tie_2")
		(at 119.38 165.1 0)
		(mirror y)
		(unit 1)
		(exclude_from_sim no)
		(in_bom yes)
		(on_board yes)
		(dnp no)
		(fields_autoplaced yes)
		(property "Reference" "NT16"
			(at 119.38 163.83 0)
			(effects
				(font
					(size 1.27 1.27)
				)
				(hide yes)
			)
		)
		(property "Value" "Net-Tie_2"
			(at 97.79 167.64 0)
			(effects
				(font
					(size 1.27 1.27)
					(thickness 0.15)
				)
				(justify left bottom)
				(hide yes)
			)
		)
		(property "Footprint" "antmicro-footprints:NetTie-2_SMD_Pad0.127mm"
			(at 97.79 170.18 0)
			(effects
				(font
					(size 1.27 1.27)
					(thickness 0.15)
				)
				(justify left bottom)
				(hide yes)
			)
		)
		(property "Datasheet" ""
			(at 97.79 172.72 0)
			(effects
				(font
					(size 1.27 1.27)
					(thickness 0.15)
				)
				(justify left bottom)
				(hide yes)
			)
		)
		(property "Description" ""
			(at 119.38 165.1 0)
			(effects
				(font
					(size 1.27 1.27)
				)
			)
		)
		(property "MPN" ""
			(at 97.79 173.99 0)
			(effects
				(font
					(size 1.27 1.27)
				)
				(justify left)
				(hide yes)
			)
		)
		(property "Manufacturer" ""
			(at 97.79 176.53 0)
			(effects
				(font
					(size 1.27 1.27)
				)
				(justify left)
				(hide yes)
			)
		)
		(property "Author" "Antmicro"
			(at 97.79 180.34 0)
			(effects
				(font
					(size 1.27 1.27)
					(thickness 0.15)
				)
				(justify left bottom)
				(hide yes)
			)
		)
		(property "License" "Apache-2.0"
			(at 97.79 182.88 0)
			(effects
				(font
					(size 1.27 1.27)
					(thickness 0.15)
				)
				(justify left bottom)
				(hide yes)
			)
		)
		(pin "1"
		)
		(pin "2"
		)
		(instances
			(project "k410t-devboard"
				(path ""
					(reference "NT16")
					(unit 1)
				)
			)
		)
	)
	(symbol
		(lib_id "antmicroCapacitors0603:C_47u_0603")
		(at 125.73 77.47 90)
		(unit 1)
		(exclude_from_sim no)
		(in_bom yes)
		(on_board yes)
		(dnp no)
		(property "Reference" "C3"
			(at 126.365 73.025 90)
			(effects
				(font
					(size 1.27 1.27)
				)
				(justify right)
			)
		)
		(property "Value" "C_47u_0603"
			(at 135.89 57.15 0)
			(effects
				(font
					(size 1.27 1.27)
					(thickness 0.15)
				)
				(justify left bottom)
				(hide yes)
			)
		)
		(property "Footprint" "antmicro-footprints:C_0603_1608Metric"
			(at 138.43 57.15 0)
			(effects
				(font
					(size 1.27 1.27)
					(thickness 0.15)
				)
				(justify left bottom)
				(hide yes)
			)
		)
		(property "Datasheet" "https://www.murata.com/products/productdetail?partno=GRM188R60J476ME15%23"
			(at 140.97 57.15 0)
			(effects
				(font
					(size 1.27 1.27)
					(thickness 0.15)
				)
				(justify left bottom)
				(hide yes)
			)
		)
		(property "Description" ""
			(at 125.73 77.47 0)
			(effects
				(font
					(size 1.27 1.27)
				)
			)
		)
		(property "Manufacturer" "Murata"
			(at 146.05 57.15 0)
			(effects
				(font
					(size 1.27 1.27)
					(thickness 0.15)
				)
				(justify left bottom)
				(hide yes)
			)
		)
		(property "MPN" "GRM188R60J476ME15D"
			(at 143.51 57.15 0)
			(effects
				(font
					(size 1.27 1.27)
					(thickness 0.15)
				)
				(justify left bottom)
				(hide yes)
			)
		)
		(property "Val" "47u"
			(at 126.365 76.835 90)
			(effects
				(font
					(size 1.27 1.27)
					(thickness 0.15)
				)
				(justify right)
			)
		)
		(property "License" "Apache-2.0"
			(at 148.59 57.15 0)
			(effects
				(font
					(size 1.27 1.27)
					(thickness 0.15)
				)
				(justify left bottom)
				(hide yes)
			)
		)
		(property "Author" "Antmicro"
			(at 151.13 57.15 0)
			(effects
				(font
					(size 1.27 1.27)
					(thickness 0.15)
				)
				(justify left bottom)
				(hide yes)
			)
		)
		(property "Voltage" ""
			(at 153.67 57.15 0)
			(effects
				(font
					(size 1.27 1.27)
				)
				(justify left bottom)
				(hide yes)
			)
		)
		(property "Dielectric" ""
			(at 156.21 57.15 0)
			(effects
				(font
					(size 1.27 1.27)
				)
				(justify left bottom)
				(hide yes)
			)
		)
		(pin "1"
		)
		(pin "2"
		)
		(instances
			(project "k410t-devboard"
				(path ""
					(reference "C3")
					(unit 1)
				)
			)
		)
	)
	(symbol
		(lib_id "antmicroCapacitors0402:C_100n_0402")
		(at 248.92 77.47 270)
		(mirror x)
		(unit 1)
		(exclude_from_sim no)
		(in_bom yes)
		(on_board yes)
		(dnp no)
		(property "Reference" "C36"
			(at 248.285 73.025 90)
			(effects
				(font
					(size 1.27 1.27)
				)
				(justify right)
			)
		)
		(property "Value" "C_100n_0402"
			(at 238.76 57.15 0)
			(effects
				(font
					(size 1.27 1.27)
					(thickness 0.15)
				)
				(justify left bottom)
				(hide yes)
			)
		)
		(property "Footprint" "antmicro-footprints:C_0402_1005Metric"
			(at 236.22 57.15 0)
			(effects
				(font
					(size 1.27 1.27)
					(thickness 0.15)
				)
				(justify left bottom)
				(hide yes)
			)
		)
		(property "Datasheet" "https://www.murata.com/products/productdetail?partno=GRM155R61H104KE14%23"
			(at 233.68 57.15 0)
			(effects
				(font
					(size 1.27 1.27)
					(thickness 0.15)
				)
				(justify left bottom)
				(hide yes)
			)
		)
		(property "Description" ""
			(at 248.92 77.47 0)
			(effects
				(font
					(size 1.27 1.27)
				)
			)
		)
		(property "Manufacturer" "Murata"
			(at 228.6 57.15 0)
			(effects
				(font
					(size 1.27 1.27)
					(thickness 0.15)
				)
				(justify left bottom)
				(hide yes)
			)
		)
		(property "MPN" "GRM155R61H104KE14D"
			(at 231.14 57.15 0)
			(effects
				(font
					(size 1.27 1.27)
					(thickness 0.15)
				)
				(justify left bottom)
				(hide yes)
			)
		)
		(property "Val" "100n"
			(at 248.285 76.835 90)
			(effects
				(font
					(size 1.27 1.27)
					(thickness 0.15)
				)
				(justify right)
			)
		)
		(property "License" "Apache-2.0"
			(at 226.06 57.15 0)
			(effects
				(font
					(size 1.27 1.27)
					(thickness 0.15)
				)
				(justify left bottom)
				(hide yes)
			)
		)
		(property "Author" "Antmicro"
			(at 223.52 57.15 0)
			(effects
				(font
					(size 1.27 1.27)
					(thickness 0.15)
				)
				(justify left bottom)
				(hide yes)
			)
		)
		(property "Voltage" "50V"
			(at 220.98 57.15 0)
			(effects
				(font
					(size 1.27 1.27)
				)
				(justify left bottom)
				(hide yes)
			)
		)
		(property "Dielectric" "X5R"
			(at 218.44 57.15 0)
			(effects
				(font
					(size 1.27 1.27)
				)
				(justify left bottom)
				(hide yes)
			)
		)
		(pin "1"
		)
		(pin "2"
		)
		(instances
			(project "k410t-devboard"
				(path ""
					(reference "C36")
					(unit 1)
				)
			)
		)
	)
	(symbol
		(lib_id "antmicroCapacitors0402:C_100n_0402")
		(at 271.78 77.47 270)
		(mirror x)
		(unit 1)
		(exclude_from_sim no)
		(in_bom yes)
		(on_board yes)
		(dnp no)
		(property "Reference" "C18"
			(at 271.145 73.025 90)
			(effects
				(font
					(size 1.27 1.27)
				)
				(justify right)
			)
		)
		(property "Value" "C_100n_0402"
			(at 261.62 57.15 0)
			(effects
				(font
					(size 1.27 1.27)
					(thickness 0.15)
				)
				(justify left bottom)
				(hide yes)
			)
		)
		(property "Footprint" "antmicro-footprints:C_0402_1005Metric"
			(at 259.08 57.15 0)
			(effects
				(font
					(size 1.27 1.27)
					(thickness 0.15)
				)
				(justify left bottom)
				(hide yes)
			)
		)
		(property "Datasheet" "https://www.murata.com/products/productdetail?partno=GRM155R61H104KE14%23"
			(at 256.54 57.15 0)
			(effects
				(font
					(size 1.27 1.27)
					(thickness 0.15)
				)
				(justify left bottom)
				(hide yes)
			)
		)
		(property "Description" ""
			(at 271.78 77.47 0)
			(effects
				(font
					(size 1.27 1.27)
				)
			)
		)
		(property "Manufacturer" "Murata"
			(at 251.46 57.15 0)
			(effects
				(font
					(size 1.27 1.27)
					(thickness 0.15)
				)
				(justify left bottom)
				(hide yes)
			)
		)
		(property "MPN" "GRM155R61H104KE14D"
			(at 254 57.15 0)
			(effects
				(font
					(size 1.27 1.27)
					(thickness 0.15)
				)
				(justify left bottom)
				(hide yes)
			)
		)
		(property "Val" "100n"
			(at 271.145 76.835 90)
			(effects
				(font
					(size 1.27 1.27)
					(thickness 0.15)
				)
				(justify right)
			)
		)
		(property "License" "Apache-2.0"
			(at 248.92 57.15 0)
			(effects
				(font
					(size 1.27 1.27)
					(thickness 0.15)
				)
				(justify left bottom)
				(hide yes)
			)
		)
		(property "Author" "Antmicro"
			(at 246.38 57.15 0)
			(effects
				(font
					(size 1.27 1.27)
					(thickness 0.15)
				)
				(justify left bottom)
				(hide yes)
			)
		)
		(property "Voltage" "50V"
			(at 243.84 57.15 0)
			(effects
				(font
					(size 1.27 1.27)
				)
				(justify left bottom)
				(hide yes)
			)
		)
		(property "Dielectric" "X5R"
			(at 241.3 57.15 0)
			(effects
				(font
					(size 1.27 1.27)
				)
				(justify left bottom)
				(hide yes)
			)
		)
		(pin "1"
		)
		(pin "2"
		)
		(instances
			(project "k410t-devboard"
				(path ""
					(reference "C18")
					(unit 1)
				)
			)
		)
	)
	(symbol
		(lib_id "antmicroCapacitors0402:C_100n_0402")
		(at 156.21 77.47 90)
		(unit 1)
		(exclude_from_sim no)
		(in_bom yes)
		(on_board yes)
		(dnp no)
		(property "Reference" "C29"
			(at 156.845 73.025 90)
			(effects
				(font
					(size 1.27 1.27)
				)
				(justify right)
			)
		)
		(property "Value" "C_100n_0402"
			(at 166.37 57.15 0)
			(effects
				(font
					(size 1.27 1.27)
					(thickness 0.15)
				)
				(justify left bottom)
				(hide yes)
			)
		)
		(property "Footprint" "antmicro-footprints:C_0402_1005Metric"
			(at 168.91 57.15 0)
			(effects
				(font
					(size 1.27 1.27)
					(thickness 0.15)
				)
				(justify left bottom)
				(hide yes)
			)
		)
		(property "Datasheet" "https://www.murata.com/products/productdetail?partno=GRM155R61H104KE14%23"
			(at 171.45 57.15 0)
			(effects
				(font
					(size 1.27 1.27)
					(thickness 0.15)
				)
				(justify left bottom)
				(hide yes)
			)
		)
		(property "Description" ""
			(at 156.21 77.47 0)
			(effects
				(font
					(size 1.27 1.27)
				)
			)
		)
		(property "Manufacturer" "Murata"
			(at 176.53 57.15 0)
			(effects
				(font
					(size 1.27 1.27)
					(thickness 0.15)
				)
				(justify left bottom)
				(hide yes)
			)
		)
		(property "MPN" "GRM155R61H104KE14D"
			(at 173.99 57.15 0)
			(effects
				(font
					(size 1.27 1.27)
					(thickness 0.15)
				)
				(justify left bottom)
				(hide yes)
			)
		)
		(property "Val" "100n"
			(at 156.845 76.835 90)
			(effects
				(font
					(size 1.27 1.27)
					(thickness 0.15)
				)
				(justify right)
			)
		)
		(property "License" "Apache-2.0"
			(at 179.07 57.15 0)
			(effects
				(font
					(size 1.27 1.27)
					(thickness 0.15)
				)
				(justify left bottom)
				(hide yes)
			)
		)
		(property "Author" "Antmicro"
			(at 181.61 57.15 0)
			(effects
				(font
					(size 1.27 1.27)
					(thickness 0.15)
				)
				(justify left bottom)
				(hide yes)
			)
		)
		(property "Voltage" "50V"
			(at 184.15 57.15 0)
			(effects
				(font
					(size 1.27 1.27)
				)
				(justify left bottom)
				(hide yes)
			)
		)
		(property "Dielectric" "X5R"
			(at 186.69 57.15 0)
			(effects
				(font
					(size 1.27 1.27)
				)
				(justify left bottom)
				(hide yes)
			)
		)
		(pin "1"
		)
		(pin "2"
		)
		(instances
			(project "k410t-devboard"
				(path ""
					(reference "C29")
					(unit 1)
				)
			)
		)
	)
	(symbol
		(lib_id "antmicroCapacitors0402:C_100n_0402")
		(at 279.4 77.47 270)
		(mirror x)
		(unit 1)
		(exclude_from_sim no)
		(in_bom yes)
		(on_board yes)
		(dnp no)
		(property "Reference" "C12"
			(at 278.765 73.025 90)
			(effects
				(font
					(size 1.27 1.27)
				)
				(justify right)
			)
		)
		(property "Value" "C_100n_0402"
			(at 269.24 57.15 0)
			(effects
				(font
					(size 1.27 1.27)
					(thickness 0.15)
				)
				(justify left bottom)
				(hide yes)
			)
		)
		(property "Footprint" "antmicro-footprints:C_0402_1005Metric"
			(at 266.7 57.15 0)
			(effects
				(font
					(size 1.27 1.27)
					(thickness 0.15)
				)
				(justify left bottom)
				(hide yes)
			)
		)
		(property "Datasheet" "https://www.murata.com/products/productdetail?partno=GRM155R61H104KE14%23"
			(at 264.16 57.15 0)
			(effects
				(font
					(size 1.27 1.27)
					(thickness 0.15)
				)
				(justify left bottom)
				(hide yes)
			)
		)
		(property "Description" ""
			(at 279.4 77.47 0)
			(effects
				(font
					(size 1.27 1.27)
				)
			)
		)
		(property "Manufacturer" "Murata"
			(at 259.08 57.15 0)
			(effects
				(font
					(size 1.27 1.27)
					(thickness 0.15)
				)
				(justify left bottom)
				(hide yes)
			)
		)
		(property "MPN" "GRM155R61H104KE14D"
			(at 261.62 57.15 0)
			(effects
				(font
					(size 1.27 1.27)
					(thickness 0.15)
				)
				(justify left bottom)
				(hide yes)
			)
		)
		(property "Val" "100n"
			(at 278.765 76.835 90)
			(effects
				(font
					(size 1.27 1.27)
					(thickness 0.15)
				)
				(justify right)
			)
		)
		(property "License" "Apache-2.0"
			(at 256.54 57.15 0)
			(effects
				(font
					(size 1.27 1.27)
					(thickness 0.15)
				)
				(justify left bottom)
				(hide yes)
			)
		)
		(property "Author" "Antmicro"
			(at 254 57.15 0)
			(effects
				(font
					(size 1.27 1.27)
					(thickness 0.15)
				)
				(justify left bottom)
				(hide yes)
			)
		)
		(property "Voltage" "50V"
			(at 251.46 57.15 0)
			(effects
				(font
					(size 1.27 1.27)
				)
				(justify left bottom)
				(hide yes)
			)
		)
		(property "Dielectric" "X5R"
			(at 248.92 57.15 0)
			(effects
				(font
					(size 1.27 1.27)
				)
				(justify left bottom)
				(hide yes)
			)
		)
		(pin "1"
		)
		(pin "2"
		)
		(instances
			(project "k410t-devboard"
				(path ""
					(reference "C12")
					(unit 1)
				)
			)
		)
	)
	(symbol
		(lib_id "antmicroCapacitors0402:C_100n_0402")
		(at 163.83 77.47 90)
		(unit 1)
		(exclude_from_sim no)
		(in_bom yes)
		(on_board yes)
		(dnp no)
		(property "Reference" "C35"
			(at 164.465 73.025 90)
			(effects
				(font
					(size 1.27 1.27)
				)
				(justify right)
			)
		)
		(property "Value" "C_100n_0402"
			(at 173.99 57.15 0)
			(effects
				(font
					(size 1.27 1.27)
					(thickness 0.15)
				)
				(justify left bottom)
				(hide yes)
			)
		)
		(property "Footprint" "antmicro-footprints:C_0402_1005Metric"
			(at 176.53 57.15 0)
			(effects
				(font
					(size 1.27 1.27)
					(thickness 0.15)
				)
				(justify left bottom)
				(hide yes)
			)
		)
		(property "Datasheet" "https://www.murata.com/products/productdetail?partno=GRM155R61H104KE14%23"
			(at 179.07 57.15 0)
			(effects
				(font
					(size 1.27 1.27)
					(thickness 0.15)
				)
				(justify left bottom)
				(hide yes)
			)
		)
		(property "Description" ""
			(at 163.83 77.47 0)
			(effects
				(font
					(size 1.27 1.27)
				)
			)
		)
		(property "Manufacturer" "Murata"
			(at 184.15 57.15 0)
			(effects
				(font
					(size 1.27 1.27)
					(thickness 0.15)
				)
				(justify left bottom)
				(hide yes)
			)
		)
		(property "MPN" "GRM155R61H104KE14D"
			(at 181.61 57.15 0)
			(effects
				(font
					(size 1.27 1.27)
					(thickness 0.15)
				)
				(justify left bottom)
				(hide yes)
			)
		)
		(property "Val" "100n"
			(at 164.465 76.835 90)
			(effects
				(font
					(size 1.27 1.27)
					(thickness 0.15)
				)
				(justify right)
			)
		)
		(property "License" "Apache-2.0"
			(at 186.69 57.15 0)
			(effects
				(font
					(size 1.27 1.27)
					(thickness 0.15)
				)
				(justify left bottom)
				(hide yes)
			)
		)
		(property "Author" "Antmicro"
			(at 189.23 57.15 0)
			(effects
				(font
					(size 1.27 1.27)
					(thickness 0.15)
				)
				(justify left bottom)
				(hide yes)
			)
		)
		(property "Voltage" "50V"
			(at 191.77 57.15 0)
			(effects
				(font
					(size 1.27 1.27)
				)
				(justify left bottom)
				(hide yes)
			)
		)
		(property "Dielectric" "X5R"
			(at 194.31 57.15 0)
			(effects
				(font
					(size 1.27 1.27)
				)
				(justify left bottom)
				(hide yes)
			)
		)
		(pin "1"
		)
		(pin "2"
		)
		(instances
			(project "k410t-devboard"
				(path ""
					(reference "C35")
					(unit 1)
				)
			)
		)
	)
	(symbol
		(lib_id "antmicropower:GND")
		(at 287.02 81.28 0)
		(mirror y)
		(unit 1)
		(exclude_from_sim no)
		(in_bom yes)
		(on_board yes)
		(dnp no)
		(property "Reference" "#PWR010"
			(at 287.02 87.63 0)
			(effects
				(font
					(size 1.27 1.27)
				)
				(hide yes)
			)
		)
		(property "Value" "GND"
			(at 287.02 85.09 0)
			(effects
				(font
					(size 1.27 1.27)
				)
			)
		)
		(property "Footprint" ""
			(at 278.13 88.9 0)
			(effects
				(font
					(size 1.27 1.27)
					(thickness 0.15)
				)
				(justify left bottom)
				(hide yes)
			)
		)
		(property "Datasheet" ""
			(at 278.13 93.98 0)
			(effects
				(font
					(size 1.27 1.27)
					(thickness 0.15)
				)
				(justify left bottom)
				(hide yes)
			)
		)
		(property "Description" ""
			(at 287.02 81.28 0)
			(effects
				(font
					(size 1.27 1.27)
				)
			)
		)
		(property "Author" "Antmicro"
			(at 278.13 88.9 0)
			(effects
				(font
					(size 1.27 1.27)
					(thickness 0.15)
				)
				(justify left bottom)
				(hide yes)
			)
		)
		(property "License" "Apache-2.0"
			(at 278.13 91.44 0)
			(effects
				(font
					(size 1.27 1.27)
					(thickness 0.15)
				)
				(justify left bottom)
				(hide yes)
			)
		)
		(pin "1"
		)
		(instances
			(project "k410t-devboard"
				(path ""
					(reference "#PWR010")
					(unit 1)
				)
			)
		)
	)
	(symbol
		(lib_id "antmicroCapacitors0402:C_100n_0402")
		(at 256.54 77.47 270)
		(mirror x)
		(unit 1)
		(exclude_from_sim no)
		(in_bom yes)
		(on_board yes)
		(dnp no)
		(property "Reference" "C30"
			(at 255.905 73.025 90)
			(effects
				(font
					(size 1.27 1.27)
				)
				(justify right)
			)
		)
		(property "Value" "C_100n_0402"
			(at 246.38 57.15 0)
			(effects
				(font
					(size 1.27 1.27)
					(thickness 0.15)
				)
				(justify left bottom)
				(hide yes)
			)
		)
		(property "Footprint" "antmicro-footprints:C_0402_1005Metric"
			(at 243.84 57.15 0)
			(effects
				(font
					(size 1.27 1.27)
					(thickness 0.15)
				)
				(justify left bottom)
				(hide yes)
			)
		)
		(property "Datasheet" "https://www.murata.com/products/productdetail?partno=GRM155R61H104KE14%23"
			(at 241.3 57.15 0)
			(effects
				(font
					(size 1.27 1.27)
					(thickness 0.15)
				)
				(justify left bottom)
				(hide yes)
			)
		)
		(property "Description" ""
			(at 256.54 77.47 0)
			(effects
				(font
					(size 1.27 1.27)
				)
			)
		)
		(property "Manufacturer" "Murata"
			(at 236.22 57.15 0)
			(effects
				(font
					(size 1.27 1.27)
					(thickness 0.15)
				)
				(justify left bottom)
				(hide yes)
			)
		)
		(property "MPN" "GRM155R61H104KE14D"
			(at 238.76 57.15 0)
			(effects
				(font
					(size 1.27 1.27)
					(thickness 0.15)
				)
				(justify left bottom)
				(hide yes)
			)
		)
		(property "Val" "100n"
			(at 255.905 76.835 90)
			(effects
				(font
					(size 1.27 1.27)
					(thickness 0.15)
				)
				(justify right)
			)
		)
		(property "License" "Apache-2.0"
			(at 233.68 57.15 0)
			(effects
				(font
					(size 1.27 1.27)
					(thickness 0.15)
				)
				(justify left bottom)
				(hide yes)
			)
		)
		(property "Author" "Antmicro"
			(at 231.14 57.15 0)
			(effects
				(font
					(size 1.27 1.27)
					(thickness 0.15)
				)
				(justify left bottom)
				(hide yes)
			)
		)
		(property "Voltage" "50V"
			(at 228.6 57.15 0)
			(effects
				(font
					(size 1.27 1.27)
				)
				(justify left bottom)
				(hide yes)
			)
		)
		(property "Dielectric" "X5R"
			(at 226.06 57.15 0)
			(effects
				(font
					(size 1.27 1.27)
				)
				(justify left bottom)
				(hide yes)
			)
		)
		(pin "1"
		)
		(pin "2"
		)
		(instances
			(project "k410t-devboard"
				(path ""
					(reference "C30")
					(unit 1)
				)
			)
		)
	)
	(symbol
		(lib_id "antmicropower:+3.3V")
		(at 121.92 68.58 0)
		(unit 1)
		(exclude_from_sim no)
		(in_bom yes)
		(on_board yes)
		(dnp no)
		(fields_autoplaced yes)
		(property "Reference" "#PWR04"
			(at 121.92 72.39 0)
			(effects
				(font
					(size 1.27 1.27)
				)
				(hide yes)
			)
		)
		(property "Value" "+3V3"
			(at 121.92 65.024 0)
			(effects
				(font
					(size 1.27 1.27)
				)
			)
		)
		(property "Footprint" ""
			(at 121.92 68.58 0)
			(effects
				(font
					(size 1.27 1.27)
				)
				(hide yes)
			)
		)
		(property "Datasheet" ""
			(at 121.92 68.58 0)
			(effects
				(font
					(size 1.27 1.27)
				)
				(hide yes)
			)
		)
		(property "Description" ""
			(at 121.92 68.58 0)
			(effects
				(font
					(size 1.27 1.27)
				)
			)
		)
		(pin "1"
		)
		(instances
			(project "k410t-devboard"
				(path ""
					(reference "#PWR04")
					(unit 1)
				)
			)
		)
	)
	(symbol
		(lib_id "antmicroCapacitors0402:C_100n_0402")
		(at 241.3 77.47 270)
		(mirror x)
		(unit 1)
		(exclude_from_sim no)
		(in_bom yes)
		(on_board yes)
		(dnp no)
		(property "Reference" "C41"
			(at 240.665 73.025 90)
			(effects
				(font
					(size 1.27 1.27)
				)
				(justify right)
			)
		)
		(property "Value" "C_100n_0402"
			(at 231.14 57.15 0)
			(effects
				(font
					(size 1.27 1.27)
					(thickness 0.15)
				)
				(justify left bottom)
				(hide yes)
			)
		)
		(property "Footprint" "antmicro-footprints:C_0402_1005Metric"
			(at 228.6 57.15 0)
			(effects
				(font
					(size 1.27 1.27)
					(thickness 0.15)
				)
				(justify left bottom)
				(hide yes)
			)
		)
		(property "Datasheet" "https://www.murata.com/products/productdetail?partno=GRM155R61H104KE14%23"
			(at 226.06 57.15 0)
			(effects
				(font
					(size 1.27 1.27)
					(thickness 0.15)
				)
				(justify left bottom)
				(hide yes)
			)
		)
		(property "Description" ""
			(at 241.3 77.47 0)
			(effects
				(font
					(size 1.27 1.27)
				)
			)
		)
		(property "Manufacturer" "Murata"
			(at 220.98 57.15 0)
			(effects
				(font
					(size 1.27 1.27)
					(thickness 0.15)
				)
				(justify left bottom)
				(hide yes)
			)
		)
		(property "MPN" "GRM155R61H104KE14D"
			(at 223.52 57.15 0)
			(effects
				(font
					(size 1.27 1.27)
					(thickness 0.15)
				)
				(justify left bottom)
				(hide yes)
			)
		)
		(property "Val" "100n"
			(at 240.665 76.835 90)
			(effects
				(font
					(size 1.27 1.27)
					(thickness 0.15)
				)
				(justify right)
			)
		)
		(property "License" "Apache-2.0"
			(at 218.44 57.15 0)
			(effects
				(font
					(size 1.27 1.27)
					(thickness 0.15)
				)
				(justify left bottom)
				(hide yes)
			)
		)
		(property "Author" "Antmicro"
			(at 215.9 57.15 0)
			(effects
				(font
					(size 1.27 1.27)
					(thickness 0.15)
				)
				(justify left bottom)
				(hide yes)
			)
		)
		(property "Voltage" "50V"
			(at 213.36 57.15 0)
			(effects
				(font
					(size 1.27 1.27)
				)
				(justify left bottom)
				(hide yes)
			)
		)
		(property "Dielectric" "X5R"
			(at 210.82 57.15 0)
			(effects
				(font
					(size 1.27 1.27)
				)
				(justify left bottom)
				(hide yes)
			)
		)
		(pin "1"
		)
		(pin "2"
		)
		(instances
			(project "k410t-devboard"
				(path ""
					(reference "C41")
					(unit 1)
				)
			)
		)
	)
	(symbol
		(lib_id "k410t-devboard:Net-Tie_2")
		(at 119.38 187.96 0)
		(mirror y)
		(unit 1)
		(exclude_from_sim no)
		(in_bom yes)
		(on_board yes)
		(dnp no)
		(fields_autoplaced yes)
		(property "Reference" "NT18"
			(at 119.38 186.69 0)
			(effects
				(font
					(size 1.27 1.27)
				)
				(hide yes)
			)
		)
		(property "Value" "Net-Tie_2"
			(at 97.79 190.5 0)
			(effects
				(font
					(size 1.27 1.27)
					(thickness 0.15)
				)
				(justify left bottom)
				(hide yes)
			)
		)
		(property "Footprint" "antmicro-footprints:NetTie-2_SMD_Pad0.127mm"
			(at 97.79 193.04 0)
			(effects
				(font
					(size 1.27 1.27)
					(thickness 0.15)
				)
				(justify left bottom)
				(hide yes)
			)
		)
		(property "Datasheet" ""
			(at 97.79 195.58 0)
			(effects
				(font
					(size 1.27 1.27)
					(thickness 0.15)
				)
				(justify left bottom)
				(hide yes)
			)
		)
		(property "Description" ""
			(at 119.38 187.96 0)
			(effects
				(font
					(size 1.27 1.27)
				)
			)
		)
		(property "MPN" ""
			(at 97.79 196.85 0)
			(effects
				(font
					(size 1.27 1.27)
				)
				(justify left)
				(hide yes)
			)
		)
		(property "Manufacturer" ""
			(at 97.79 199.39 0)
			(effects
				(font
					(size 1.27 1.27)
				)
				(justify left)
				(hide yes)
			)
		)
		(property "Author" "Antmicro"
			(at 97.79 203.2 0)
			(effects
				(font
					(size 1.27 1.27)
					(thickness 0.15)
				)
				(justify left bottom)
				(hide yes)
			)
		)
		(property "License" "Apache-2.0"
			(at 97.79 205.74 0)
			(effects
				(font
					(size 1.27 1.27)
					(thickness 0.15)
				)
				(justify left bottom)
				(hide yes)
			)
		)
		(pin "1"
		)
		(pin "2"
		)
		(instances
			(project "k410t-devboard"
				(path ""
					(reference "NT18")
					(unit 1)
				)
			)
		)
	)
	(symbol
		(lib_id "antmicroCapacitors0402:C_100n_0402")
		(at 148.59 77.47 90)
		(unit 1)
		(exclude_from_sim no)
		(in_bom yes)
		(on_board yes)
		(dnp no)
		(property "Reference" "C23"
			(at 149.225 73.025 90)
			(effects
				(font
					(size 1.27 1.27)
				)
				(justify right)
			)
		)
		(property "Value" "C_100n_0402"
			(at 158.75 57.15 0)
			(effects
				(font
					(size 1.27 1.27)
					(thickness 0.15)
				)
				(justify left bottom)
				(hide yes)
			)
		)
		(property "Footprint" "antmicro-footprints:C_0402_1005Metric"
			(at 161.29 57.15 0)
			(effects
				(font
					(size 1.27 1.27)
					(thickness 0.15)
				)
				(justify left bottom)
				(hide yes)
			)
		)
		(property "Datasheet" "https://www.murata.com/products/productdetail?partno=GRM155R61H104KE14%23"
			(at 163.83 57.15 0)
			(effects
				(font
					(size 1.27 1.27)
					(thickness 0.15)
				)
				(justify left bottom)
				(hide yes)
			)
		)
		(property "Description" ""
			(at 148.59 77.47 0)
			(effects
				(font
					(size 1.27 1.27)
				)
			)
		)
		(property "Manufacturer" "Murata"
			(at 168.91 57.15 0)
			(effects
				(font
					(size 1.27 1.27)
					(thickness 0.15)
				)
				(justify left bottom)
				(hide yes)
			)
		)
		(property "MPN" "GRM155R61H104KE14D"
			(at 166.37 57.15 0)
			(effects
				(font
					(size 1.27 1.27)
					(thickness 0.15)
				)
				(justify left bottom)
				(hide yes)
			)
		)
		(property "Val" "100n"
			(at 149.225 76.835 90)
			(effects
				(font
					(size 1.27 1.27)
					(thickness 0.15)
				)
				(justify right)
			)
		)
		(property "License" "Apache-2.0"
			(at 171.45 57.15 0)
			(effects
				(font
					(size 1.27 1.27)
					(thickness 0.15)
				)
				(justify left bottom)
				(hide yes)
			)
		)
		(property "Author" "Antmicro"
			(at 173.99 57.15 0)
			(effects
				(font
					(size 1.27 1.27)
					(thickness 0.15)
				)
				(justify left bottom)
				(hide yes)
			)
		)
		(property "Voltage" "50V"
			(at 176.53 57.15 0)
			(effects
				(font
					(size 1.27 1.27)
				)
				(justify left bottom)
				(hide yes)
			)
		)
		(property "Dielectric" "X5R"
			(at 179.07 57.15 0)
			(effects
				(font
					(size 1.27 1.27)
				)
				(justify left bottom)
				(hide yes)
			)
		)
		(pin "1"
		)
		(pin "2"
		)
		(instances
			(project "k410t-devboard"
				(path ""
					(reference "C23")
					(unit 1)
				)
			)
		)
	)
	(symbol
		(lib_id "antmicroFPGAChips:XC7K410T-2FFG900I")
		(at 177.8 100.33 0)
		(unit 1)
		(exclude_from_sim no)
		(in_bom yes)
		(on_board yes)
		(dnp no)
		(fields_autoplaced yes)
		(property "Reference" "U1"
			(at 205.74 90.805 0)
			(effects
				(font
					(size 1.27 1.27)
					(thickness 0.15)
				)
			)
		)
		(property "Value" "XC7K410T-2FFG900I"
			(at 205.74 93.345 0)
			(effects
				(font
					(size 1.27 1.27)
					(thickness 0.15)
				)
			)
		)
		(property "Footprint" "antmicro-footprints:BGA-900_31x31mm_Layout30x30_P1x1mm_FFG900"
			(at 177.8 73.66 0)
			(effects
				(font
					(size 1.27 1.27)
					(thickness 0.15)
				)
				(justify left bottom)
				(hide yes)
			)
		)
		(property "Datasheet" "https://eu.mouser.com/datasheet/2/903/ds180_7Series_Overview-1591537.pdf"
			(at 177.8 76.2 0)
			(effects
				(font
					(size 1.27 1.27)
					(thickness 0.15)
				)
				(justify left bottom)
				(hide yes)
			)
		)
		(property "Description" ""
			(at 177.8 100.33 0)
			(effects
				(font
					(size 1.27 1.27)
				)
			)
		)
		(property "Manufacturer" "AMD-Xilinx"
			(at 177.8 78.74 0)
			(effects
				(font
					(size 1.27 1.27)
					(thickness 0.15)
				)
				(justify left bottom)
				(hide yes)
			)
		)
		(property "MPN" "XC7K410T-2FFG900I"
			(at 177.8 81.28 0)
			(effects
				(font
					(size 1.27 1.27)
					(thickness 0.15)
				)
				(justify left bottom)
				(hide yes)
			)
		)
		(property "Author" "Antmicro"
			(at 177.8 83.82 0)
			(effects
				(font
					(size 1.27 1.27)
					(thickness 0.15)
				)
				(justify left bottom)
				(hide yes)
			)
		)
		(property "License" "Apache-2.0"
			(at 177.8 86.36 0)
			(effects
				(font
					(size 1.27 1.27)
					(thickness 0.15)
				)
				(justify left bottom)
				(hide yes)
			)
		)
		(pin "AA20"
		)
		(pin "AA21"
		)
		(pin "AA22"
		)
		(pin "AA23"
		)
		(pin "AB20"
		)
		(pin "AB22"
		)
		(pin "AB23"
		)
		(pin "AB24"
		)
		(pin "AC20"
		)
		(pin "AC21"
		)
		(pin "AC22"
		)
		(pin "AC24"
		)
		(pin "AC25"
		)
		(pin "AD21"
		)
		(pin "AD22"
		)
		(pin "AD23"
		)
		(pin "AD24"
		)
		(pin "AE20"
		)
		(pin "AE21"
		)
		(pin "AE23"
		)
		(pin "AE24"
		)
		(pin "AE25"
		)
		(pin "AF20"
		)
		(pin "AF21"
		)
		(pin "AF22"
		)
		(pin "AF23"
		)
		(pin "AF25"
		)
		(pin "AG20"
		)
		(pin "AG22"
		)
		(pin "AG23"
		)
		(pin "AG24"
		)
		(pin "AG25"
		)
		(pin "AH20"
		)
		(pin "AH21"
		)
		(pin "AH22"
		)
		(pin "AH24"
		)
		(pin "AH25"
		)
		(pin "AJ21"
		)
		(pin "AJ22"
		)
		(pin "AJ23"
		)
		(pin "AJ24"
		)
		(pin "AK20"
		)
		(pin "AK21"
		)
		(pin "AK23"
		)
		(pin "AK24"
		)
		(pin "AK25"
		)
		(pin "Y20"
		)
		(pin "Y21"
		)
		(pin "Y23"
		)
		(pin "Y24"
		)
		(pin "E30"
		)
		(pin "E28"
		)
		(pin "E29"
		)
		(pin "P24"
		)
		(pin "P26"
		)
		(pin "P27"
		)
		(pin "P28"
		)
		(pin "P29"
		)
		(pin "R19"
		)
		(pin "R20"
		)
		(pin "R21"
		)
		(pin "R23"
		)
		(pin "R24"
		)
		(pin "R25"
		)
		(pin "R26"
		)
		(pin "R28"
		)
		(pin "R29"
		)
		(pin "R30"
		)
		(pin "T20"
		)
		(pin "T21"
		)
		(pin "T22"
		)
		(pin "T23"
		)
		(pin "T25"
		)
		(pin "T26"
		)
		(pin "T27"
		)
		(pin "T28"
		)
		(pin "T30"
		)
		(pin "U19"
		)
		(pin "U20"
		)
		(pin "U22"
		)
		(pin "U23"
		)
		(pin "U24"
		)
		(pin "U25"
		)
		(pin "U27"
		)
		(pin "U28"
		)
		(pin "U29"
		)
		(pin "U30"
		)
		(pin "V19"
		)
		(pin "V20"
		)
		(pin "V21"
		)
		(pin "V22"
		)
		(pin "V24"
		)
		(pin "V25"
		)
		(pin "V26"
		)
		(pin "V27"
		)
		(pin "V29"
		)
		(pin "V30"
		)
		(pin "W19"
		)
		(pin "W21"
		)
		(pin "W22"
		)
		(pin "W23"
		)
		(pin "W24"
		)
		(pin "W26"
		)
		(pin "A23"
		)
		(pin "A25"
		)
		(pin "A26"
		)
		(pin "A27"
		)
		(pin "A28"
		)
		(pin "A30"
		)
		(pin "B23"
		)
		(pin "B24"
		)
		(pin "B25"
		)
		(pin "B27"
		)
		(pin "B28"
		)
		(pin "B29"
		)
		(pin "B30"
		)
		(pin "C24"
		)
		(pin "C25"
		)
		(pin "C26"
		)
		(pin "C27"
		)
		(pin "C29"
		)
		(pin "C30"
		)
		(pin "D23"
		)
		(pin "D24"
		)
		(pin "D26"
		)
		(pin "D27"
		)
		(pin "D28"
		)
		(pin "D29"
		)
		(pin "E23"
		)
		(pin "E24"
		)
		(pin "E25"
		)
		(pin "E26"
		)
		(pin "B2"
		)
		(pin "B5"
		)
		(pin "B6"
		)
		(pin "C3"
		)
		(pin "C4"
		)
		(pin "C7"
		)
		(pin "F23"
		)
		(pin "F25"
		)
		(pin "F26"
		)
		(pin "F27"
		)
		(pin "F28"
		)
		(pin "F30"
		)
		(pin "G23"
		)
		(pin "G24"
		)
		(pin "G25"
		)
		(pin "G27"
		)
		(pin "G28"
		)
		(pin "G29"
		)
		(pin "G30"
		)
		(pin "H24"
		)
		(pin "H25"
		)
		(pin "H26"
		)
		(pin "H27"
		)
		(pin "H30"
		)
		(pin "A11"
		)
		(pin "A12"
		)
		(pin "A13"
		)
		(pin "A15"
		)
		(pin "B12"
		)
		(pin "B13"
		)
		(pin "B14"
		)
		(pin "B15"
		)
		(pin "C11"
		)
		(pin "C12"
		)
		(pin "C14"
		)
		(pin "C15"
		)
		(pin "D11"
		)
		(pin "D12"
		)
		(pin "D13"
		)
		(pin "D14"
		)
		(pin "E11"
		)
		(pin "E13"
		)
		(pin "E14"
		)
		(pin "E15"
		)
		(pin "E16"
		)
		(pin "F11"
		)
		(pin "F12"
		)
		(pin "F13"
		)
		(pin "F15"
		)
		(pin "F16"
		)
		(pin "G12"
		)
		(pin "G13"
		)
		(pin "G14"
		)
		(pin "G15"
		)
		(pin "H11"
		)
		(pin "H12"
		)
		(pin "H14"
		)
		(pin "H15"
		)
		(pin "H16"
		)
		(pin "J11"
		)
		(pin "J12"
		)
		(pin "J13"
		)
		(pin "J14"
		)
		(pin "J16"
		)
		(pin "K11"
		)
		(pin "K13"
		)
		(pin "K14"
		)
		(pin "K15"
		)
		(pin "K16"
		)
		(pin "L11"
		)
		(pin "L12"
		)
		(pin "L13"
		)
		(pin "L15"
		)
		(pin "L16"
		)
		(pin "AA10"
		)
		(pin "AA11"
		)
		(pin "AA12"
		)
		(pin "AA13"
		)
		(pin "AA8"
		)
		(pin "AB10"
		)
		(pin "AB12"
		)
		(pin "AB13"
		)
		(pin "AB8"
		)
		(pin "AB9"
		)
		(pin "AC10"
		)
		(pin "AC11"
		)
		(pin "AC12"
		)
		(pin "AC9"
		)
		(pin "AD11"
		)
		(pin "AD12"
		)
		(pin "AD13"
		)
		(pin "AD8"
		)
		(pin "AD9"
		)
		(pin "AE10"
		)
		(pin "AE11"
		)
		(pin "AE13"
		)
		(pin "AE8"
		)
		(pin "AE9"
		)
		(pin "AF10"
		)
		(pin "AF11"
		)
		(pin "AF12"
		)
		(pin "AF13"
		)
		(pin "AG10"
		)
		(pin "AG12"
		)
		(pin "AG13"
		)
		(pin "AG9"
		)
		(pin "AH10"
		)
		(pin "AH11"
		)
		(pin "AH12"
		)
		(pin "AH14"
		)
		(pin "AH9"
		)
		(pin "AJ11"
		)
		(pin "AJ12"
		)
		(pin "AJ13"
		)
		(pin "AJ14"
		)
		(pin "AJ9"
		)
		(pin "AK10"
		)
		(pin "AK11"
		)
		(pin "AK13"
		)
		(pin "AK14"
		)
		(pin "AK9"
		)
		(pin "Y10"
		)
		(pin "Y11"
		)
		(pin "Y13"
		)
		(pin "A3"
		)
		(pin "A4"
		)
		(pin "A7"
		)
		(pin "A8"
		)
		(pin "AA3"
		)
		(pin "AA4"
		)
		(pin "B1"
		)
		(pin "G16"
		)
		(pin "G2"
		)
		(pin "G26"
		)
		(pin "G6"
		)
		(pin "G9"
		)
		(pin "H13"
		)
		(pin "H23"
		)
		(pin "H4"
		)
		(pin "H8"
		)
		(pin "H9"
		)
		(pin "J1"
		)
		(pin "J10"
		)
		(pin "C8"
		)
		(pin "D1"
		)
		(pin "D2"
		)
		(pin "D5"
		)
		(pin "D6"
		)
		(pin "E3"
		)
		(pin "E4"
		)
		(pin "E7"
		)
		(pin "E8"
		)
		(pin "F1"
		)
		(pin "F2"
		)
		(pin "F5"
		)
		(pin "F6"
		)
		(pin "G3"
		)
		(pin "G4"
		)
		(pin "G7"
		)
		(pin "G8"
		)
		(pin "H1"
		)
		(pin "H2"
		)
		(pin "H5"
		)
		(pin "H6"
		)
		(pin "J3"
		)
		(pin "J4"
		)
		(pin "J7"
		)
		(pin "J8"
		)
		(pin "K1"
		)
		(pin "K2"
		)
		(pin "K5"
		)
		(pin "K6"
		)
		(pin "L3"
		)
		(pin "L4"
		)
		(pin "L7"
		)
		(pin "L8"
		)
		(pin "M1"
		)
		(pin "M2"
		)
		(pin "M5"
		)
		(pin "M6"
		)
		(pin "N3"
		)
		(pin "N4"
		)
		(pin "N7"
		)
		(pin "N8"
		)
		(pin "P1"
		)
		(pin "P2"
		)
		(pin "P5"
		)
		(pin "P6"
		)
		(pin "R3"
		)
		(pin "R4"
		)
		(pin "R7"
		)
		(pin "R8"
		)
		(pin "T1"
		)
		(pin "T2"
		)
		(pin "T5"
		)
		(pin "T6"
		)
		(pin "U3"
		)
		(pin "U4"
		)
		(pin "U7"
		)
		(pin "U8"
		)
		(pin "V1"
		)
		(pin "V2"
		)
		(pin "V5"
		)
		(pin "V6"
		)
		(pin "W3"
		)
		(pin "W4"
		)
		(pin "Y1"
		)
		(pin "Y2"
		)
		(pin "Y5"
		)
		(pin "Y6"
		)
		(pin "B3"
		)
		(pin "B7"
		)
		(pin "C5"
		)
		(pin "D3"
		)
		(pin "D7"
		)
		(pin "E5"
		)
		(pin "F3"
		)
		(pin "F7"
		)
		(pin "G5"
		)
		(pin "H3"
		)
		(pin "H7"
		)
		(pin "J5"
		)
		(pin "K3"
		)
		(pin "K7"
		)
		(pin "L5"
		)
		(pin "M3"
		)
		(pin "M7"
		)
		(pin "N5"
		)
		(pin "P3"
		)
		(pin "P7"
		)
		(pin "R5"
		)
		(pin "T3"
		)
		(pin "T7"
		)
		(pin "U5"
		)
		(pin "V3"
		)
		(pin "V7"
		)
		(pin "W5"
		)
		(pin "W7"
		)
		(pin "W8"
		)
		(pin "A10"
		)
		(pin "AB1"
		)
		(pin "AB2"
		)
		(pin "AB5"
		)
		(pin "B10"
		)
		(pin "E10"
		)
		(pin "F10"
		)
		(pin "G10"
		)
		(pin "H10"
		)
		(pin "K10"
		)
		(pin "L10"
		)
		(pin "M10"
		)
		(pin "R14"
		)
		(pin "R15"
		)
		(pin "T14"
		)
		(pin "T15"
		)
		(pin "U14"
		)
		(pin "U15"
		)
		(pin "A19"
		)
		(pin "A29"
		)
		(pin "AA19"
		)
		(pin "AA29"
		)
		(pin "AA9"
		)
		(pin "AB16"
		)
		(pin "AB26"
		)
		(pin "AB6"
		)
		(pin "AC13"
		)
		(pin "AC23"
		)
		(pin "AC3"
		)
		(pin "AD10"
		)
		(pin "AD20"
		)
		(pin "AD30"
		)
		(pin "AE17"
		)
		(pin "AE27"
		)
		(pin "AE7"
		)
		(pin "AF14"
		)
		(pin "AF24"
		)
		(pin "AF4"
		)
		(pin "AG1"
		)
		(pin "AG11"
		)
		(pin "AG21"
		)
		(pin "AH18"
		)
		(pin "AH28"
		)
		(pin "AH8"
		)
		(pin "AJ15"
		)
		(pin "AJ25"
		)
		(pin "AJ5"
		)
		(pin "AK12"
		)
		(pin "AK2"
		)
		(pin "AK22"
		)
		(pin "B16"
		)
		(pin "B26"
		)
		(pin "C13"
		)
		(pin "C23"
		)
		(pin "D10"
		)
		(pin "D20"
		)
		(pin "D30"
		)
		(pin "E17"
		)
		(pin "E27"
		)
		(pin "F14"
		)
		(pin "F24"
		)
		(pin "G11"
		)
		(pin "G21"
		)
		(pin "H18"
		)
		(pin "H28"
		)
		(pin "J15"
		)
		(pin "J25"
		)
		(pin "K12"
		)
		(pin "K22"
		)
		(pin "L19"
		)
		(pin "L29"
		)
		(pin "M26"
		)
		(pin "N23"
		)
		(pin "P20"
		)
		(pin "P30"
		)
		(pin "R27"
		)
		(pin "T24"
		)
		(pin "T9"
		)
		(pin "U21"
		)
		(pin "V28"
		)
		(pin "W25"
		)
		(pin "Y12"
		)
		(pin "Y22"
		)
		(pin "A1"
		)
		(pin "A14"
		)
		(pin "A2"
		)
		(pin "A24"
		)
		(pin "A5"
		)
		(pin "A6"
		)
		(pin "A9"
		)
		(pin "AA1"
		)
		(pin "AA14"
		)
		(pin "AA2"
		)
		(pin "AA24"
		)
		(pin "AA5"
		)
		(pin "AA6"
		)
		(pin "AA7"
		)
		(pin "AB11"
		)
		(pin "AB21"
		)
		(pin "AB3"
		)
		(pin "AB4"
		)
		(pin "AC18"
		)
		(pin "AC28"
		)
		(pin "AC8"
		)
		(pin "AD15"
		)
		(pin "AD25"
		)
		(pin "AD5"
		)
		(pin "AE12"
		)
		(pin "AE2"
		)
		(pin "AE22"
		)
		(pin "AF19"
		)
		(pin "AF29"
		)
		(pin "AF9"
		)
		(pin "AG16"
		)
		(pin "AG26"
		)
		(pin "AG6"
		)
		(pin "AH13"
		)
		(pin "AH23"
		)
		(pin "AH3"
		)
		(pin "AJ10"
		)
		(pin "AJ20"
		)
		(pin "AJ30"
		)
		(pin "AK17"
		)
		(pin "AK27"
		)
		(pin "AK7"
		)
		(pin "B11"
		)
		(pin "B21"
		)
		(pin "B4"
		)
		(pin "B8"
		)
		(pin "B9"
		)
		(pin "C1"
		)
		(pin "C10"
		)
		(pin "C18"
		)
		(pin "C2"
		)
		(pin "C28"
		)
		(pin "C6"
		)
		(pin "C9"
		)
		(pin "D15"
		)
		(pin "D25"
		)
		(pin "D4"
		)
		(pin "D8"
		)
		(pin "D9"
		)
		(pin "E1"
		)
		(pin "E12"
		)
		(pin "E2"
		)
		(pin "E22"
		)
		(pin "E6"
		)
		(pin "E9"
		)
		(pin "F19"
		)
		(pin "F29"
		)
		(pin "F4"
		)
		(pin "F8"
		)
		(pin "F9"
		)
		(pin "G1"
		)
		(pin "J2"
		)
		(pin "J20"
		)
		(pin "J30"
		)
		(pin "J6"
		)
		(pin "J9"
		)
		(pin "K17"
		)
		(pin "K27"
		)
		(pin "K4"
		)
		(pin "K8"
		)
		(pin "K9"
		)
		(pin "L1"
		)
		(pin "L14"
		)
		(pin "L2"
		)
		(pin "L24"
		)
		(pin "L6"
		)
		(pin "L9"
		)
		(pin "M11"
		)
		(pin "M12"
		)
		(pin "M13"
		)
		(pin "M14"
		)
		(pin "M15"
		)
		(pin "M16"
		)
		(pin "M17"
		)
		(pin "M18"
		)
		(pin "M21"
		)
		(pin "M4"
		)
		(pin "M8"
		)
		(pin "M9"
		)
		(pin "N1"
		)
		(pin "N10"
		)
		(pin "N11"
		)
		(pin "N12"
		)
		(pin "N13"
		)
		(pin "N14"
		)
		(pin "N15"
		)
		(pin "N16"
		)
		(pin "N17"
		)
		(pin "N18"
		)
		(pin "N2"
		)
		(pin "N28"
		)
		(pin "N6"
		)
		(pin "N9"
		)
		(pin "P10"
		)
		(pin "P11"
		)
		(pin "P12"
		)
		(pin "P13"
		)
		(pin "P14"
		)
		(pin "P15"
		)
		(pin "P16"
		)
		(pin "P17"
		)
		(pin "P18"
		)
		(pin "P25"
		)
		(pin "P4"
		)
		(pin "P8"
		)
		(pin "P9"
		)
		(pin "R1"
		)
		(pin "R10"
		)
		(pin "R11"
		)
		(pin "R12"
		)
		(pin "R13"
		)
		(pin "R16"
		)
		(pin "R17"
		)
		(pin "R18"
		)
		(pin "R2"
		)
		(pin "R22"
		)
		(pin "R6"
		)
		(pin "R9"
		)
		(pin "T10"
		)
		(pin "T11"
		)
		(pin "T12"
		)
		(pin "T13"
		)
		(pin "T16"
		)
		(pin "T17"
		)
		(pin "T18"
		)
		(pin "T19"
		)
		(pin "T29"
		)
		(pin "T4"
		)
		(pin "T8"
		)
		(pin "U1"
		)
		(pin "U10"
		)
		(pin "U11"
		)
		(pin "U12"
		)
		(pin "U13"
		)
		(pin "U16"
		)
		(pin "U17"
		)
		(pin "U18"
		)
		(pin "U2"
		)
		(pin "U26"
		)
		(pin "U6"
		)
		(pin "U9"
		)
		(pin "V10"
		)
		(pin "V11"
		)
		(pin "V12"
		)
		(pin "V13"
		)
		(pin "V14"
		)
		(pin "V15"
		)
		(pin "V16"
		)
		(pin "V17"
		)
		(pin "V18"
		)
		(pin "V23"
		)
		(pin "V4"
		)
		(pin "V8"
		)
		(pin "V9"
		)
		(pin "W1"
		)
		(pin "W10"
		)
		(pin "W11"
		)
		(pin "W12"
		)
		(pin "W13"
		)
		(pin "W14"
		)
		(pin "W15"
		)
		(pin "W16"
		)
		(pin "W17"
		)
		(pin "W18"
		)
		(pin "W2"
		)
		(pin "W20"
		)
		(pin "W30"
		)
		(pin "W6"
		)
		(pin "W9"
		)
		(pin "Y17"
		)
		(pin "Y27"
		)
		(pin "Y3"
		)
		(pin "Y4"
		)
		(pin "Y7"
		)
		(pin "Y8"
		)
		(pin "Y9"
		)
		(pin "AA25"
		)
		(pin "AA26"
		)
		(pin "AA27"
		)
		(pin "AA28"
		)
		(pin "AA30"
		)
		(pin "AB25"
		)
		(pin "AB27"
		)
		(pin "AB28"
		)
		(pin "AB29"
		)
		(pin "AB30"
		)
		(pin "AC26"
		)
		(pin "AC27"
		)
		(pin "AC29"
		)
		(pin "AC30"
		)
		(pin "AD26"
		)
		(pin "AD27"
		)
		(pin "AD28"
		)
		(pin "AD29"
		)
		(pin "AE26"
		)
		(pin "AE28"
		)
		(pin "AE29"
		)
		(pin "AE30"
		)
		(pin "AF26"
		)
		(pin "AF27"
		)
		(pin "AF28"
		)
		(pin "AF30"
		)
		(pin "AG27"
		)
		(pin "AG28"
		)
		(pin "AG29"
		)
		(pin "AG30"
		)
		(pin "AH26"
		)
		(pin "AH27"
		)
		(pin "AH29"
		)
		(pin "AH30"
		)
		(pin "AJ26"
		)
		(pin "AJ27"
		)
		(pin "AJ28"
		)
		(pin "AJ29"
		)
		(pin "AK26"
		)
		(pin "AK28"
		)
		(pin "AK29"
		)
		(pin "AK30"
		)
		(pin "W27"
		)
		(pin "W28"
		)
		(pin "W29"
		)
		(pin "Y25"
		)
		(pin "Y26"
		)
		(pin "Y28"
		)
		(pin "Y29"
		)
		(pin "Y30"
		)
		(pin "H29"
		)
		(pin "J21"
		)
		(pin "J22"
		)
		(pin "J23"
		)
		(pin "J24"
		)
		(pin "J26"
		)
		(pin "J27"
		)
		(pin "J28"
		)
		(pin "J29"
		)
		(pin "K21"
		)
		(pin "K23"
		)
		(pin "K24"
		)
		(pin "K25"
		)
		(pin "K26"
		)
		(pin "K28"
		)
		(pin "K29"
		)
		(pin "K30"
		)
		(pin "L20"
		)
		(pin "L21"
		)
		(pin "L22"
		)
		(pin "L23"
		)
		(pin "L25"
		)
		(pin "L26"
		)
		(pin "L27"
		)
		(pin "L28"
		)
		(pin "L30"
		)
		(pin "M19"
		)
		(pin "M20"
		)
		(pin "M22"
		)
		(pin "M23"
		)
		(pin "M24"
		)
		(pin "M25"
		)
		(pin "M27"
		)
		(pin "M28"
		)
		(pin "M29"
		)
		(pin "M30"
		)
		(pin "N19"
		)
		(pin "N20"
		)
		(pin "N21"
		)
		(pin "N22"
		)
		(pin "N24"
		)
		(pin "N25"
		)
		(pin "N26"
		)
		(pin "N27"
		)
		(pin "N29"
		)
		(pin "N30"
		)
		(pin "P19"
		)
		(pin "P21"
		)
		(pin "P22"
		)
		(pin "P23"
		)
		(pin "A16"
		)
		(pin "A17"
		)
		(pin "A18"
		)
		(pin "A20"
		)
		(pin "A21"
		)
		(pin "A22"
		)
		(pin "B17"
		)
		(pin "B18"
		)
		(pin "B19"
		)
		(pin "B20"
		)
		(pin "B22"
		)
		(pin "C16"
		)
		(pin "C17"
		)
		(pin "C19"
		)
		(pin "C20"
		)
		(pin "C21"
		)
		(pin "C22"
		)
		(pin "D16"
		)
		(pin "D17"
		)
		(pin "D18"
		)
		(pin "D19"
		)
		(pin "D21"
		)
		(pin "D22"
		)
		(pin "E18"
		)
		(pin "E19"
		)
		(pin "E20"
		)
		(pin "E21"
		)
		(pin "F17"
		)
		(pin "F18"
		)
		(pin "F20"
		)
		(pin "F21"
		)
		(pin "F22"
		)
		(pin "G17"
		)
		(pin "G18"
		)
		(pin "G19"
		)
		(pin "G20"
		)
		(pin "G22"
		)
		(pin "H17"
		)
		(pin "H19"
		)
		(pin "H20"
		)
		(pin "H21"
		)
		(pin "H22"
		)
		(pin "J17"
		)
		(pin "J18"
		)
		(pin "J19"
		)
		(pin "K18"
		)
		(pin "K19"
		)
		(pin "K20"
		)
		(pin "L17"
		)
		(pin "L18"
		)
		(pin "AA15"
		)
		(pin "AA16"
		)
		(pin "AA17"
		)
		(pin "AA18"
		)
		(pin "AB14"
		)
		(pin "AB15"
		)
		(pin "AB17"
		)
		(pin "AB18"
		)
		(pin "AB19"
		)
		(pin "AC14"
		)
		(pin "AC15"
		)
		(pin "AC16"
		)
		(pin "AC17"
		)
		(pin "AC19"
		)
		(pin "AD14"
		)
		(pin "AD16"
		)
		(pin "AD17"
		)
		(pin "AD18"
		)
		(pin "AD19"
		)
		(pin "AE14"
		)
		(pin "AE15"
		)
		(pin "AE16"
		)
		(pin "AE18"
		)
		(pin "AE19"
		)
		(pin "AF15"
		)
		(pin "AF16"
		)
		(pin "AF17"
		)
		(pin "AF18"
		)
		(pin "AG14"
		)
		(pin "AG15"
		)
		(pin "AG17"
		)
		(pin "AG18"
		)
		(pin "AG19"
		)
		(pin "AH15"
		)
		(pin "AH16"
		)
		(pin "AH17"
		)
		(pin "AH19"
		)
		(pin "AJ16"
		)
		(pin "AJ17"
		)
		(pin "AJ18"
		)
		(pin "AJ19"
		)
		(pin "AK15"
		)
		(pin "AK16"
		)
		(pin "AK18"
		)
		(pin "AK19"
		)
		(pin "Y14"
		)
		(pin "Y15"
		)
		(pin "Y16"
		)
		(pin "Y18"
		)
		(pin "Y19"
		)
		(pin "AB7"
		)
		(pin "AC1"
		)
		(pin "AC2"
		)
		(pin "AC4"
		)
		(pin "AC5"
		)
		(pin "AC6"
		)
		(pin "AC7"
		)
		(pin "AD1"
		)
		(pin "AD2"
		)
		(pin "AD3"
		)
		(pin "AD4"
		)
		(pin "AD6"
		)
		(pin "AD7"
		)
		(pin "AE1"
		)
		(pin "AE3"
		)
		(pin "AE4"
		)
		(pin "AE5"
		)
		(pin "AE6"
		)
		(pin "AF1"
		)
		(pin "AF2"
		)
		(pin "AF3"
		)
		(pin "AF5"
		)
		(pin "AF6"
		)
		(pin "AF7"
		)
		(pin "AF8"
		)
		(pin "AG2"
		)
		(pin "AG3"
		)
		(pin "AG4"
		)
		(pin "AG5"
		)
		(pin "AG7"
		)
		(pin "AG8"
		)
		(pin "AH1"
		)
		(pin "AH2"
		)
		(pin "AH4"
		)
		(pin "AH5"
		)
		(pin "AH6"
		)
		(pin "AH7"
		)
		(pin "AJ1"
		)
		(pin "AJ2"
		)
		(pin "AJ3"
		)
		(pin "AJ4"
		)
		(pin "AJ6"
		)
		(pin "AJ7"
		)
		(pin "AJ8"
		)
		(pin "AK1"
		)
		(pin "AK3"
		)
		(pin "AK4"
		)
		(pin "AK5"
		)
		(pin "AK6"
		)
		(pin "AK8"
		)
		(instances
			(project "k410t-devboard"
				(path ""
					(reference "U1")
					(unit 1)
				)
			)
		)
	)
	(symbol
		(lib_id "antmicroCapacitors0402:C_100n_0402")
		(at 171.45 77.47 90)
		(unit 1)
		(exclude_from_sim no)
		(in_bom yes)
		(on_board yes)
		(dnp no)
		(property "Reference" "C40"
			(at 172.085 73.025 90)
			(effects
				(font
					(size 1.27 1.27)
				)
				(justify right)
			)
		)
		(property "Value" "C_100n_0402"
			(at 181.61 57.15 0)
			(effects
				(font
					(size 1.27 1.27)
					(thickness 0.15)
				)
				(justify left bottom)
				(hide yes)
			)
		)
		(property "Footprint" "antmicro-footprints:C_0402_1005Metric"
			(at 184.15 57.15 0)
			(effects
				(font
					(size 1.27 1.27)
					(thickness 0.15)
				)
				(justify left bottom)
				(hide yes)
			)
		)
		(property "Datasheet" "https://www.murata.com/products/productdetail?partno=GRM155R61H104KE14%23"
			(at 186.69 57.15 0)
			(effects
				(font
					(size 1.27 1.27)
					(thickness 0.15)
				)
				(justify left bottom)
				(hide yes)
			)
		)
		(property "Description" ""
			(at 171.45 77.47 0)
			(effects
				(font
					(size 1.27 1.27)
				)
			)
		)
		(property "Manufacturer" "Murata"
			(at 191.77 57.15 0)
			(effects
				(font
					(size 1.27 1.27)
					(thickness 0.15)
				)
				(justify left bottom)
				(hide yes)
			)
		)
		(property "MPN" "GRM155R61H104KE14D"
			(at 189.23 57.15 0)
			(effects
				(font
					(size 1.27 1.27)
					(thickness 0.15)
				)
				(justify left bottom)
				(hide yes)
			)
		)
		(property "Val" "100n"
			(at 172.085 76.835 90)
			(effects
				(font
					(size 1.27 1.27)
					(thickness 0.15)
				)
				(justify right)
			)
		)
		(property "License" "Apache-2.0"
			(at 194.31 57.15 0)
			(effects
				(font
					(size 1.27 1.27)
					(thickness 0.15)
				)
				(justify left bottom)
				(hide yes)
			)
		)
		(property "Author" "Antmicro"
			(at 196.85 57.15 0)
			(effects
				(font
					(size 1.27 1.27)
					(thickness 0.15)
				)
				(justify left bottom)
				(hide yes)
			)
		)
		(property "Voltage" "50V"
			(at 199.39 57.15 0)
			(effects
				(font
					(size 1.27 1.27)
				)
				(justify left bottom)
				(hide yes)
			)
		)
		(property "Dielectric" "X5R"
			(at 201.93 57.15 0)
			(effects
				(font
					(size 1.27 1.27)
				)
				(justify left bottom)
				(hide yes)
			)
		)
		(pin "1"
		)
		(pin "2"
		)
		(instances
			(project "k410t-devboard"
				(path ""
					(reference "C40")
					(unit 1)
				)
			)
		)
	)
	(symbol
		(lib_id "k410t-devboard:Net-Tie_2")
		(at 119.38 170.18 0)
		(mirror y)
		(unit 1)
		(exclude_from_sim no)
		(in_bom yes)
		(on_board yes)
		(dnp no)
		(fields_autoplaced yes)
		(property "Reference" "NT17"
			(at 119.38 168.91 0)
			(effects
				(font
					(size 1.27 1.27)
				)
				(hide yes)
			)
		)
		(property "Value" "Net-Tie_2"
			(at 97.79 172.72 0)
			(effects
				(font
					(size 1.27 1.27)
					(thickness 0.15)
				)
				(justify left bottom)
				(hide yes)
			)
		)
		(property "Footprint" "antmicro-footprints:NetTie-2_SMD_Pad0.127mm"
			(at 97.79 175.26 0)
			(effects
				(font
					(size 1.27 1.27)
					(thickness 0.15)
				)
				(justify left bottom)
				(hide yes)
			)
		)
		(property "Datasheet" ""
			(at 97.79 177.8 0)
			(effects
				(font
					(size 1.27 1.27)
					(thickness 0.15)
				)
				(justify left bottom)
				(hide yes)
			)
		)
		(property "Description" ""
			(at 119.38 170.18 0)
			(effects
				(font
					(size 1.27 1.27)
				)
			)
		)
		(property "MPN" ""
			(at 97.79 179.07 0)
			(effects
				(font
					(size 1.27 1.27)
				)
				(justify left)
				(hide yes)
			)
		)
		(property "Manufacturer" ""
			(at 97.79 181.61 0)
			(effects
				(font
					(size 1.27 1.27)
				)
				(justify left)
				(hide yes)
			)
		)
		(property "Author" "Antmicro"
			(at 97.79 185.42 0)
			(effects
				(font
					(size 1.27 1.27)
					(thickness 0.15)
				)
				(justify left bottom)
				(hide yes)
			)
		)
		(property "License" "Apache-2.0"
			(at 97.79 187.96 0)
			(effects
				(font
					(size 1.27 1.27)
					(thickness 0.15)
				)
				(justify left bottom)
				(hide yes)
			)
		)
		(pin "1"
		)
		(pin "2"
		)
		(instances
			(project "k410t-devboard"
				(path ""
					(reference "NT17")
					(unit 1)
				)
			)
		)
	)
	(symbol
		(lib_id "antmicroCapacitors0402:C_100n_0402")
		(at 140.97 77.47 90)
		(unit 1)
		(exclude_from_sim no)
		(in_bom yes)
		(on_board yes)
		(dnp no)
		(property "Reference" "C17"
			(at 141.605 73.025 90)
			(effects
				(font
					(size 1.27 1.27)
				)
				(justify right)
			)
		)
		(property "Value" "C_100n_0402"
			(at 151.13 57.15 0)
			(effects
				(font
					(size 1.27 1.27)
					(thickness 0.15)
				)
				(justify left bottom)
				(hide yes)
			)
		)
		(property "Footprint" "antmicro-footprints:C_0402_1005Metric"
			(at 153.67 57.15 0)
			(effects
				(font
					(size 1.27 1.27)
					(thickness 0.15)
				)
				(justify left bottom)
				(hide yes)
			)
		)
		(property "Datasheet" "https://www.murata.com/products/productdetail?partno=GRM155R61H104KE14%23"
			(at 156.21 57.15 0)
			(effects
				(font
					(size 1.27 1.27)
					(thickness 0.15)
				)
				(justify left bottom)
				(hide yes)
			)
		)
		(property "Description" ""
			(at 140.97 77.47 0)
			(effects
				(font
					(size 1.27 1.27)
				)
			)
		)
		(property "Manufacturer" "Murata"
			(at 161.29 57.15 0)
			(effects
				(font
					(size 1.27 1.27)
					(thickness 0.15)
				)
				(justify left bottom)
				(hide yes)
			)
		)
		(property "MPN" "GRM155R61H104KE14D"
			(at 158.75 57.15 0)
			(effects
				(font
					(size 1.27 1.27)
					(thickness 0.15)
				)
				(justify left bottom)
				(hide yes)
			)
		)
		(property "Val" "100n"
			(at 141.605 76.835 90)
			(effects
				(font
					(size 1.27 1.27)
					(thickness 0.15)
				)
				(justify right)
			)
		)
		(property "License" "Apache-2.0"
			(at 163.83 57.15 0)
			(effects
				(font
					(size 1.27 1.27)
					(thickness 0.15)
				)
				(justify left bottom)
				(hide yes)
			)
		)
		(property "Author" "Antmicro"
			(at 166.37 57.15 0)
			(effects
				(font
					(size 1.27 1.27)
					(thickness 0.15)
				)
				(justify left bottom)
				(hide yes)
			)
		)
		(property "Voltage" "50V"
			(at 168.91 57.15 0)
			(effects
				(font
					(size 1.27 1.27)
				)
				(justify left bottom)
				(hide yes)
			)
		)
		(property "Dielectric" "X5R"
			(at 171.45 57.15 0)
			(effects
				(font
					(size 1.27 1.27)
				)
				(justify left bottom)
				(hide yes)
			)
		)
		(pin "1"
		)
		(pin "2"
		)
		(instances
			(project "k410t-devboard"
				(path ""
					(reference "C17")
					(unit 1)
				)
			)
		)
	)
	(symbol
		(lib_id "antmicroCapacitors0402:C_100n_0402")
		(at 264.16 77.47 270)
		(mirror x)
		(unit 1)
		(exclude_from_sim no)
		(in_bom yes)
		(on_board yes)
		(dnp no)
		(property "Reference" "C24"
			(at 263.525 73.025 90)
			(effects
				(font
					(size 1.27 1.27)
				)
				(justify right)
			)
		)
		(property "Value" "C_100n_0402"
			(at 254 57.15 0)
			(effects
				(font
					(size 1.27 1.27)
					(thickness 0.15)
				)
				(justify left bottom)
				(hide yes)
			)
		)
		(property "Footprint" "antmicro-footprints:C_0402_1005Metric"
			(at 251.46 57.15 0)
			(effects
				(font
					(size 1.27 1.27)
					(thickness 0.15)
				)
				(justify left bottom)
				(hide yes)
			)
		)
		(property "Datasheet" "https://www.murata.com/products/productdetail?partno=GRM155R61H104KE14%23"
			(at 248.92 57.15 0)
			(effects
				(font
					(size 1.27 1.27)
					(thickness 0.15)
				)
				(justify left bottom)
				(hide yes)
			)
		)
		(property "Description" ""
			(at 264.16 77.47 0)
			(effects
				(font
					(size 1.27 1.27)
				)
			)
		)
		(property "Manufacturer" "Murata"
			(at 243.84 57.15 0)
			(effects
				(font
					(size 1.27 1.27)
					(thickness 0.15)
				)
				(justify left bottom)
				(hide yes)
			)
		)
		(property "MPN" "GRM155R61H104KE14D"
			(at 246.38 57.15 0)
			(effects
				(font
					(size 1.27 1.27)
					(thickness 0.15)
				)
				(justify left bottom)
				(hide yes)
			)
		)
		(property "Val" "100n"
			(at 263.525 76.835 90)
			(effects
				(font
					(size 1.27 1.27)
					(thickness 0.15)
				)
				(justify right)
			)
		)
		(property "License" "Apache-2.0"
			(at 241.3 57.15 0)
			(effects
				(font
					(size 1.27 1.27)
					(thickness 0.15)
				)
				(justify left bottom)
				(hide yes)
			)
		)
		(property "Author" "Antmicro"
			(at 238.76 57.15 0)
			(effects
				(font
					(size 1.27 1.27)
					(thickness 0.15)
				)
				(justify left bottom)
				(hide yes)
			)
		)
		(property "Voltage" "50V"
			(at 236.22 57.15 0)
			(effects
				(font
					(size 1.27 1.27)
				)
				(justify left bottom)
				(hide yes)
			)
		)
		(property "Dielectric" "X5R"
			(at 233.68 57.15 0)
			(effects
				(font
					(size 1.27 1.27)
				)
				(justify left bottom)
				(hide yes)
			)
		)
		(pin "1"
		)
		(pin "2"
		)
		(instances
			(project "k410t-devboard"
				(path ""
					(reference "C24")
					(unit 1)
				)
			)
		)
	)
	(symbol
		(lib_id "antmicroResistors0402:R_0R_0402")
		(at 256.54 218.44 0)
		(unit 1)
		(exclude_from_sim no)
		(in_bom no)
		(on_board yes)
		(dnp yes)
		(property "Reference" "R365"
			(at 264.795 217.17 0)
			(effects
				(font
					(size 1.524 1.524)
				)
			)
		)
		(property "Value" "R_0R_0402"
			(at 276.86 231.14 0)
			(effects
				(font
					(size 1.27 1.27)
					(thickness 0.15)
				)
				(justify left bottom)
				(hide yes)
			)
		)
		(property "Footprint" "antmicro-footprints:R_0402_1005Metric"
			(at 276.86 233.68 0)
			(effects
				(font
					(size 1.27 1.27)
					(thickness 0.15)
				)
				(justify left bottom)
				(hide yes)
			)
		)
		(property "Datasheet" "https://industrial.panasonic.com/cdbs/www-data/pdf/RDA0000/AOA0000C301.pdf"
			(at 276.86 236.22 0)
			(effects
				(font
					(size 1.27 1.27)
					(thickness 0.15)
				)
				(justify left bottom)
				(hide yes)
			)
		)
		(property "Description" ""
			(at 256.54 218.44 0)
			(effects
				(font
					(size 1.27 1.27)
				)
			)
		)
		(property "Manufacturer" "Panasonic"
			(at 276.86 241.3 0)
			(effects
				(font
					(size 1.27 1.27)
					(thickness 0.15)
				)
				(justify left bottom)
				(hide yes)
			)
		)
		(property "MPN" "ERJ2GE0R00X"
			(at 276.86 238.76 0)
			(effects
				(font
					(size 1.27 1.27)
					(thickness 0.15)
				)
				(justify left bottom)
				(hide yes)
			)
		)
		(property "Val" "0R"
			(at 255.27 217.17 0)
			(effects
				(font
					(size 1.27 1.27)
					(thickness 0.15)
				)
			)
		)
		(property "DNP" "DNP"
			(at 259.08 218.44 0)
			(effects
				(font
					(size 1.27 1.27)
				)
			)
		)
		(property "License" "Apache-2.0"
			(at 276.86 243.84 0)
			(effects
				(font
					(size 1.27 1.27)
					(thickness 0.15)
				)
				(justify left bottom)
				(hide yes)
			)
		)
		(property "Author" "Antmicro"
			(at 276.86 246.38 0)
			(effects
				(font
					(size 1.27 1.27)
					(thickness 0.15)
				)
				(justify left bottom)
				(hide yes)
			)
		)
		(property "Tolerance" "~"
			(at 276.86 228.6 0)
			(effects
				(font
					(size 1.27 1.27)
				)
				(justify left bottom)
				(hide yes)
			)
		)
		(property "Current" "1A"
			(at 276.86 248.92 0)
			(effects
				(font
					(size 1.27 1.27)
					(thickness 0.15)
				)
				(justify left bottom)
				(hide yes)
			)
		)
		(pin "1"
		)
		(pin "2"
		)
		(instances
			(project "k410t-devboard"
				(path ""
					(reference "R365")
					(unit 1)
				)
			)
		)
	)
	(symbol
		(lib_id "antmicroCapacitors0603:C_47u_0603")
		(at 287.02 77.47 270)
		(mirror x)
		(unit 1)
		(exclude_from_sim no)
		(in_bom yes)
		(on_board yes)
		(dnp no)
		(property "Reference" "C4"
			(at 286.385 73.025 90)
			(effects
				(font
					(size 1.27 1.27)
				)
				(justify right)
			)
		)
		(property "Value" "C_47u_0603"
			(at 276.86 57.15 0)
			(effects
				(font
					(size 1.27 1.27)
					(thickness 0.15)
				)
				(justify left bottom)
				(hide yes)
			)
		)
		(property "Footprint" "antmicro-footprints:C_0603_1608Metric"
			(at 274.32 57.15 0)
			(effects
				(font
					(size 1.27 1.27)
					(thickness 0.15)
				)
				(justify left bottom)
				(hide yes)
			)
		)
		(property "Datasheet" "https://www.murata.com/products/productdetail?partno=GRM188R60J476ME15%23"
			(at 271.78 57.15 0)
			(effects
				(font
					(size 1.27 1.27)
					(thickness 0.15)
				)
				(justify left bottom)
				(hide yes)
			)
		)
		(property "Description" ""
			(at 287.02 77.47 0)
			(effects
				(font
					(size 1.27 1.27)
				)
			)
		)
		(property "Manufacturer" "Murata"
			(at 266.7 57.15 0)
			(effects
				(font
					(size 1.27 1.27)
					(thickness 0.15)
				)
				(justify left bottom)
				(hide yes)
			)
		)
		(property "MPN" "GRM188R60J476ME15D"
			(at 269.24 57.15 0)
			(effects
				(font
					(size 1.27 1.27)
					(thickness 0.15)
				)
				(justify left bottom)
				(hide yes)
			)
		)
		(property "Val" "47u"
			(at 286.385 76.835 90)
			(effects
				(font
					(size 1.27 1.27)
					(thickness 0.15)
				)
				(justify right)
			)
		)
		(property "License" "Apache-2.0"
			(at 264.16 57.15 0)
			(effects
				(font
					(size 1.27 1.27)
					(thickness 0.15)
				)
				(justify left bottom)
				(hide yes)
			)
		)
		(property "Author" "Antmicro"
			(at 261.62 57.15 0)
			(effects
				(font
					(size 1.27 1.27)
					(thickness 0.15)
				)
				(justify left bottom)
				(hide yes)
			)
		)
		(property "Voltage" ""
			(at 259.08 57.15 0)
			(effects
				(font
					(size 1.27 1.27)
				)
				(justify left bottom)
				(hide yes)
			)
		)
		(property "Dielectric" ""
			(at 256.54 57.15 0)
			(effects
				(font
					(size 1.27 1.27)
				)
				(justify left bottom)
				(hide yes)
			)
		)
		(pin "1"
		)
		(pin "2"
		)
		(instances
			(project "k410t-devboard"
				(path ""
					(reference "C4")
					(unit 1)
				)
			)
		)
	)
	(symbol
		(lib_id "k410t-devboard:Net-Tie_2")
		(at 119.38 144.78 0)
		(mirror y)
		(unit 1)
		(exclude_from_sim no)
		(in_bom yes)
		(on_board yes)
		(dnp no)
		(fields_autoplaced yes)
		(property "Reference" "NT15"
			(at 119.38 143.51 0)
			(effects
				(font
					(size 1.27 1.27)
				)
				(hide yes)
			)
		)
		(property "Value" "Net-Tie_2"
			(at 97.79 147.32 0)
			(effects
				(font
					(size 1.27 1.27)
					(thickness 0.15)
				)
				(justify left bottom)
				(hide yes)
			)
		)
		(property "Footprint" "antmicro-footprints:NetTie-2_SMD_Pad0.127mm"
			(at 97.79 149.86 0)
			(effects
				(font
					(size 1.27 1.27)
					(thickness 0.15)
				)
				(justify left bottom)
				(hide yes)
			)
		)
		(property "Datasheet" ""
			(at 97.79 152.4 0)
			(effects
				(font
					(size 1.27 1.27)
					(thickness 0.15)
				)
				(justify left bottom)
				(hide yes)
			)
		)
		(property "Description" ""
			(at 119.38 144.78 0)
			(effects
				(font
					(size 1.27 1.27)
				)
			)
		)
		(property "MPN" ""
			(at 97.79 153.67 0)
			(effects
				(font
					(size 1.27 1.27)
				)
				(justify left)
				(hide yes)
			)
		)
		(property "Manufacturer" ""
			(at 97.79 156.21 0)
			(effects
				(font
					(size 1.27 1.27)
				)
				(justify left)
				(hide yes)
			)
		)
		(property "Author" "Antmicro"
			(at 97.79 160.02 0)
			(effects
				(font
					(size 1.27 1.27)
					(thickness 0.15)
				)
				(justify left bottom)
				(hide yes)
			)
		)
		(property "License" "Apache-2.0"
			(at 97.79 162.56 0)
			(effects
				(font
					(size 1.27 1.27)
					(thickness 0.15)
				)
				(justify left bottom)
				(hide yes)
			)
		)
		(pin "1"
		)
		(pin "2"
		)
		(instances
			(project "k410t-devboard"
				(path ""
					(reference "NT15")
					(unit 1)
				)
			)
		)
	)
	(symbol
		(lib_id "antmicropower:+3.3V")
		(at 290.83 68.58 0)
		(mirror y)
		(unit 1)
		(exclude_from_sim no)
		(in_bom yes)
		(on_board yes)
		(dnp no)
		(fields_autoplaced yes)
		(property "Reference" "#PWR05"
			(at 290.83 72.39 0)
			(effects
				(font
					(size 1.27 1.27)
				)
				(hide yes)
			)
		)
		(property "Value" "+3V3"
			(at 290.83 65.024 0)
			(effects
				(font
					(size 1.27 1.27)
				)
			)
		)
		(property "Footprint" ""
			(at 290.83 68.58 0)
			(effects
				(font
					(size 1.27 1.27)
				)
				(hide yes)
			)
		)
		(property "Datasheet" ""
			(at 290.83 68.58 0)
			(effects
				(font
					(size 1.27 1.27)
				)
				(hide yes)
			)
		)
		(property "Description" ""
			(at 290.83 68.58 0)
			(effects
				(font
					(size 1.27 1.27)
				)
			)
		)
		(pin "1"
		)
		(instances
			(project "k410t-devboard"
				(path ""
					(reference "#PWR05")
					(unit 1)
				)
			)
		)
	)
	(symbol
		(lib_id "antmicroCapacitors0402:C_100n_0402")
		(at 133.35 77.47 90)
		(unit 1)
		(exclude_from_sim no)
		(in_bom yes)
		(on_board yes)
		(dnp no)
		(property "Reference" "C11"
			(at 133.985 73.025 90)
			(effects
				(font
					(size 1.27 1.27)
				)
				(justify right)
			)
		)
		(property "Value" "C_100n_0402"
			(at 143.51 57.15 0)
			(effects
				(font
					(size 1.27 1.27)
					(thickness 0.15)
				)
				(justify left bottom)
				(hide yes)
			)
		)
		(property "Footprint" "antmicro-footprints:C_0402_1005Metric"
			(at 146.05 57.15 0)
			(effects
				(font
					(size 1.27 1.27)
					(thickness 0.15)
				)
				(justify left bottom)
				(hide yes)
			)
		)
		(property "Datasheet" "https://www.murata.com/products/productdetail?partno=GRM155R61H104KE14%23"
			(at 148.59 57.15 0)
			(effects
				(font
					(size 1.27 1.27)
					(thickness 0.15)
				)
				(justify left bottom)
				(hide yes)
			)
		)
		(property "Description" ""
			(at 133.35 77.47 0)
			(effects
				(font
					(size 1.27 1.27)
				)
			)
		)
		(property "Manufacturer" "Murata"
			(at 153.67 57.15 0)
			(effects
				(font
					(size 1.27 1.27)
					(thickness 0.15)
				)
				(justify left bottom)
				(hide yes)
			)
		)
		(property "MPN" "GRM155R61H104KE14D"
			(at 151.13 57.15 0)
			(effects
				(font
					(size 1.27 1.27)
					(thickness 0.15)
				)
				(justify left bottom)
				(hide yes)
			)
		)
		(property "Val" "100n"
			(at 133.985 76.835 90)
			(effects
				(font
					(size 1.27 1.27)
					(thickness 0.15)
				)
				(justify right)
			)
		)
		(property "License" "Apache-2.0"
			(at 156.21 57.15 0)
			(effects
				(font
					(size 1.27 1.27)
					(thickness 0.15)
				)
				(justify left bottom)
				(hide yes)
			)
		)
		(property "Author" "Antmicro"
			(at 158.75 57.15 0)
			(effects
				(font
					(size 1.27 1.27)
					(thickness 0.15)
				)
				(justify left bottom)
				(hide yes)
			)
		)
		(property "Voltage" "50V"
			(at 161.29 57.15 0)
			(effects
				(font
					(size 1.27 1.27)
				)
				(justify left bottom)
				(hide yes)
			)
		)
		(property "Dielectric" "X5R"
			(at 163.83 57.15 0)
			(effects
				(font
					(size 1.27 1.27)
				)
				(justify left bottom)
				(hide yes)
			)
		)
		(pin "1"
		)
		(pin "2"
		)
		(instances
			(project "k410t-devboard"
				(path ""
					(reference "C11")
					(unit 1)
				)
			)
		)
	)
	(symbol
		(lib_id "antmicroResistors0402:R_0R_0402")
		(at 256.54 220.98 0)
		(unit 1)
		(exclude_from_sim no)
		(in_bom no)
		(on_board yes)
		(dnp yes)
		(property "Reference" "R366"
			(at 264.795 219.71 0)
			(effects
				(font
					(size 1.524 1.524)
				)
			)
		)
		(property "Value" "R_0R_0402"
			(at 276.86 233.68 0)
			(effects
				(font
					(size 1.27 1.27)
					(thickness 0.15)
				)
				(justify left bottom)
				(hide yes)
			)
		)
		(property "Footprint" "antmicro-footprints:R_0402_1005Metric"
			(at 276.86 236.22 0)
			(effects
				(font
					(size 1.27 1.27)
					(thickness 0.15)
				)
				(justify left bottom)
				(hide yes)
			)
		)
		(property "Datasheet" "https://industrial.panasonic.com/cdbs/www-data/pdf/RDA0000/AOA0000C301.pdf"
			(at 276.86 238.76 0)
			(effects
				(font
					(size 1.27 1.27)
					(thickness 0.15)
				)
				(justify left bottom)
				(hide yes)
			)
		)
		(property "Description" ""
			(at 256.54 220.98 0)
			(effects
				(font
					(size 1.27 1.27)
				)
			)
		)
		(property "Manufacturer" "Panasonic"
			(at 276.86 243.84 0)
			(effects
				(font
					(size 1.27 1.27)
					(thickness 0.15)
				)
				(justify left bottom)
				(hide yes)
			)
		)
		(property "MPN" "ERJ2GE0R00X"
			(at 276.86 241.3 0)
			(effects
				(font
					(size 1.27 1.27)
					(thickness 0.15)
				)
				(justify left bottom)
				(hide yes)
			)
		)
		(property "Val" "0R"
			(at 255.27 219.71 0)
			(effects
				(font
					(size 1.27 1.27)
					(thickness 0.15)
				)
			)
		)
		(property "DNP" "DNP"
			(at 259.08 220.98 0)
			(effects
				(font
					(size 1.27 1.27)
				)
			)
		)
		(property "License" "Apache-2.0"
			(at 276.86 246.38 0)
			(effects
				(font
					(size 1.27 1.27)
					(thickness 0.15)
				)
				(justify left bottom)
				(hide yes)
			)
		)
		(property "Author" "Antmicro"
			(at 276.86 248.92 0)
			(effects
				(font
					(size 1.27 1.27)
					(thickness 0.15)
				)
				(justify left bottom)
				(hide yes)
			)
		)
		(property "Tolerance" "~"
			(at 276.86 231.14 0)
			(effects
				(font
					(size 1.27 1.27)
				)
				(justify left bottom)
				(hide yes)
			)
		)
		(property "Current" "1A"
			(at 276.86 251.46 0)
			(effects
				(font
					(size 1.27 1.27)
					(thickness 0.15)
				)
				(justify left bottom)
				(hide yes)
			)
		)
		(pin "1"
		)
		(pin "2"
		)
		(instances
			(project "k410t-devboard"
				(path ""
					(reference "R366")
					(unit 1)
				)
			)
		)
	)
)
